FILE_TYPE = MACRO_DRAWING;
SET COLOR_WIRE YELLOW;
SET COLOR_PROP ORANGE;
SET COLOR_DOT WHITE;
SET COLOR_ARC YELLOW;
SET COLOR_BODY GREEN;
SET COLOR_NOTE PURPLE;
SET PROP_DISPLAY VALUE;
SET PAGE_NUMBER P252;
FORCEADD OFFPAGE..1
(-7050 1450);
FORCEPROP 2 LAST $XR6 272 
J 0
(-7302 1486);
DISPLAY 0.638298 (-7302 1486);
PAINT MONO (-7302 1486);
FORCEPROP 2 LAST $XR5 271 
J 0
(-7542 1414);
DISPLAY 0.638298 (-7542 1414);
PAINT MONO (-7542 1414);
FORCEPROP 2 LAST $XR4 270 
J 0
(-7422 1414);
DISPLAY 0.638298 (-7422 1414);
PAINT MONO (-7422 1414);
FORCEPROP 2 LAST $XR3 269 
J 0
(-7302 1414);
DISPLAY 0.638298 (-7302 1414);
PAINT MONO (-7302 1414);
FORCEPROP 2 LAST $XR2 268 
J 0
(-7542 1450);
DISPLAY 0.638298 (-7542 1450);
PAINT MONO (-7542 1450);
FORCEPROP 2 LAST $XR1 267 
J 0
(-7422 1450);
DISPLAY 0.638298 (-7422 1450);
PAINT MONO (-7422 1450);
FORCEPROP 2 LAST $XR0 266 
J 0
(-7302 1450);
DISPLAY 0.638298 (-7302 1450);
PAINT MONO (-7302 1450);
FORCEPROP 2 LAST PATH I1
J 0
(-7300 1525);
DISPLAY 1.021277 (-7300 1525);
DISPLAY INVISIBLE (-7300 1525);
FORCEPROP 2 LAST CDS_LIB standard
J 0
(-7050 1450);
DISPLAY INVISIBLE (-7050 1450);
FORCEPROP 1 LAST OFFPAGE TRUE
J 0
(-6725 1325);
DISPLAY 0.872340 (-6725 1325);
PAINT GREEN (-6725 1325);
DISPLAY INVISIBLE (-6725 1325);
FORCEPROP 1 LAST COMMENT_BODY TRUE
J 0
(-6925 1350);
DISPLAY 0.872340 (-6925 1350);
PAINT GREEN (-6925 1350);
DISPLAY INVISIBLE (-6925 1350);
FORCEADD Q_RES..1
(-5200 1100);
FORCEPROP 1 LAST PART_NUMBER CS00002JB13
J 0
(-5075 1050);
DISPLAY 0.617021 (-5075 1050);
PAINT BLUE (-5075 1050);
DISPLAY INVISIBLE (-5075 1050);
FORCEPROP 1 LAST MATERIAL CHIP
J 0
(-5075 1000);
DISPLAY 0.617021 (-5075 1000);
PAINT SKYBLUE (-5075 1000);
FORCEPROP 1 LAST TOLERANCE 5%
J 0
(-5025 1100);
DISPLAY 0.617021 (-5025 1100);
PAINT SKYBLUE (-5025 1100);
FORCEPROP 1 LAST VALUE 0
J 2
(-5050 1100);
DISPLAY 0.617021 (-5050 1100);
PAINT SKYBLUE (-5050 1100);
FORCEPROP 1 LAST PACK_TYPE 0402LF
J 0
(-4950 1100);
DISPLAY 0.617021 (-4950 1100);
PAINT SKYBLUE (-4950 1100);
FORCEPROP 1 LAST WATTAGE 1/16W
J 2
(-4825 1000);
DISPLAY 0.617021 (-4825 1000);
PAINT SKYBLUE (-4825 1000);
FORCEPROP 1 LAST LOCATION PR156
J 0
(-5425 1100);
DISPLAY 0.617021 (-5425 1100);
PAINT AQUA (-5425 1100);
FORCEPROP 1 LASTPIN (-5300 1100) $PN 1
J 0
(-5288 1112);
DISPLAY 0.617021 (-5288 1112);
PAINT MONO (-5288 1112);
FORCEPROP 1 LASTPIN (-5100 1100) $PN 2
J 0
(-5138 1112);
DISPLAY 0.617021 (-5138 1112);
PAINT MONO (-5138 1112);
FORCEPROP 1 LAST PATH I10
J 0
(-5250 1250);
DISPLAY 0.978723 (-5250 1250);
PAINT WHITE (-5250 1250);
DISPLAY INVISIBLE (-5250 1250);
FORCEPROP 2 LAST CDS_LIB pure_quanta
J 0
(-5200 1100);
DISPLAY INVISIBLE (-5200 1100);
FORCEPROP 1 LAST LOCATION PR156
J 0
(-5250 1200);
DISPLAY 1.021277 (-5250 1200);
PAINT AQUA (-5250 1200);
DISPLAY INVISIBLE (-5250 1200);
FORCEPROP 0 LAST $SEC 1
J 0
(-5250 1200);
DISPLAY 0.680851 (-5250 1200);
PAINT MONO (-5250 1200);
DISPLAY INVISIBLE (-5250 1200);
FORCEPROP 0 LAST CDS_SEC 1
J 0
(-5250 1200);
DISPLAY 1.021277 (-5250 1200);
DISPLAY INVISIBLE (-5250 1200);
FORCEADD OFFPAGE..2
(-950 4350);
FORCEPROP 2 LAST $XR0 269 
J 0
(-761 4350);
DISPLAY 0.638298 (-761 4350);
PAINT MONO (-761 4350);
FORCEPROP 2 LAST PATH I100
J 0
(-750 4400);
DISPLAY 1.021277 (-750 4400);
DISPLAY INVISIBLE (-750 4400);
FORCEPROP 2 LAST CDS_LIB standard
J 0
(-950 4350);
DISPLAY INVISIBLE (-950 4350);
FORCEPROP 1 LAST OFFPAGE TRUE
J 0
(-625 4225);
DISPLAY 0.872340 (-625 4225);
PAINT GREEN (-625 4225);
DISPLAY INVISIBLE (-625 4225);
FORCEPROP 1 LAST COMMENT_BODY TRUE
J 0
(-995 4255);
DISPLAY 0.872340 (-995 4255);
PAINT GREEN (-995 4255);
DISPLAY INVISIBLE (-995 4255);
FORCEADD OFFPAGE..4
(-950 4250);
FORCEPROP 2 LAST $XR0 269 
J 0
(-764 4250);
DISPLAY 0.638298 (-764 4250);
PAINT MONO (-764 4250);
FORCEPROP 2 LAST PATH I101
J 0
(-750 4300);
DISPLAY 1.021277 (-750 4300);
DISPLAY INVISIBLE (-750 4300);
FORCEPROP 2 LAST CDS_LIB standard
J 0
(-950 4250);
DISPLAY INVISIBLE (-950 4250);
FORCEPROP 1 LAST OFFPAGE TRUE
J 0
(-625 4125);
DISPLAY 0.872340 (-625 4125);
PAINT GREEN (-625 4125);
DISPLAY INVISIBLE (-625 4125);
FORCEPROP 1 LAST COMMENT_BODY TRUE
J 0
(-975 4150);
DISPLAY 0.872340 (-975 4150);
PAINT GREEN (-975 4150);
DISPLAY INVISIBLE (-975 4150);
FORCEADD OFFPAGE..2
(-950 4050);
FORCEPROP 2 LAST $XR0 269 
J 0
(-761 4050);
DISPLAY 0.638298 (-761 4050);
PAINT MONO (-761 4050);
FORCEPROP 2 LAST PATH I102
J 0
(-750 4100);
DISPLAY 1.021277 (-750 4100);
DISPLAY INVISIBLE (-750 4100);
FORCEPROP 2 LAST CDS_LIB standard
J 0
(-950 4050);
DISPLAY INVISIBLE (-950 4050);
FORCEPROP 1 LAST OFFPAGE TRUE
J 0
(-625 3925);
DISPLAY 0.872340 (-625 3925);
PAINT GREEN (-625 3925);
DISPLAY INVISIBLE (-625 3925);
FORCEPROP 1 LAST COMMENT_BODY TRUE
J 0
(-995 3955);
DISPLAY 0.872340 (-995 3955);
PAINT GREEN (-995 3955);
DISPLAY INVISIBLE (-995 3955);
FORCEADD OFFPAGE..4
(-950 3950);
FORCEPROP 2 LAST $XR0 269 
J 0
(-764 3950);
DISPLAY 0.638298 (-764 3950);
PAINT MONO (-764 3950);
FORCEPROP 2 LAST PATH I103
J 0
(-750 4000);
DISPLAY 1.021277 (-750 4000);
DISPLAY INVISIBLE (-750 4000);
FORCEPROP 2 LAST CDS_LIB standard
J 0
(-950 3950);
DISPLAY INVISIBLE (-950 3950);
FORCEPROP 1 LAST OFFPAGE TRUE
J 0
(-625 3825);
DISPLAY 0.872340 (-625 3825);
PAINT GREEN (-625 3825);
DISPLAY INVISIBLE (-625 3825);
FORCEPROP 1 LAST COMMENT_BODY TRUE
J 0
(-975 3850);
DISPLAY 0.872340 (-975 3850);
PAINT GREEN (-975 3850);
DISPLAY INVISIBLE (-975 3850);
FORCEADD OFFPAGE..2
(-950 3750);
FORCEPROP 2 LAST $XR0 270 
J 0
(-761 3750);
DISPLAY 0.638298 (-761 3750);
PAINT MONO (-761 3750);
FORCEPROP 2 LAST PATH I104
J 0
(-750 3800);
DISPLAY 1.021277 (-750 3800);
DISPLAY INVISIBLE (-750 3800);
FORCEPROP 2 LAST CDS_LIB standard
J 0
(-950 3750);
DISPLAY INVISIBLE (-950 3750);
FORCEPROP 1 LAST OFFPAGE TRUE
J 0
(-625 3625);
DISPLAY 0.872340 (-625 3625);
PAINT GREEN (-625 3625);
DISPLAY INVISIBLE (-625 3625);
FORCEPROP 1 LAST COMMENT_BODY TRUE
J 0
(-995 3655);
DISPLAY 0.872340 (-995 3655);
PAINT GREEN (-995 3655);
DISPLAY INVISIBLE (-995 3655);
FORCEADD OFFPAGE..4
(-950 3650);
FORCEPROP 2 LAST $XR0 270 
J 0
(-764 3650);
DISPLAY 0.638298 (-764 3650);
PAINT MONO (-764 3650);
FORCEPROP 2 LAST PATH I105
J 0
(-750 3700);
DISPLAY 1.021277 (-750 3700);
DISPLAY INVISIBLE (-750 3700);
FORCEPROP 2 LAST CDS_LIB standard
J 0
(-950 3650);
DISPLAY INVISIBLE (-950 3650);
FORCEPROP 1 LAST OFFPAGE TRUE
J 0
(-625 3525);
DISPLAY 0.872340 (-625 3525);
PAINT GREEN (-625 3525);
DISPLAY INVISIBLE (-625 3525);
FORCEPROP 1 LAST COMMENT_BODY TRUE
J 0
(-975 3550);
DISPLAY 0.872340 (-975 3550);
PAINT GREEN (-975 3550);
DISPLAY INVISIBLE (-975 3550);
FORCEADD OFFPAGE..2
(-950 3450);
FORCEPROP 2 LAST $XR0 270 
J 0
(-761 3450);
DISPLAY 0.638298 (-761 3450);
PAINT MONO (-761 3450);
FORCEPROP 2 LAST PATH I106
J 0
(-750 3500);
DISPLAY 1.021277 (-750 3500);
DISPLAY INVISIBLE (-750 3500);
FORCEPROP 2 LAST CDS_LIB standard
J 0
(-950 3450);
DISPLAY INVISIBLE (-950 3450);
FORCEPROP 1 LAST OFFPAGE TRUE
J 0
(-625 3325);
DISPLAY 0.872340 (-625 3325);
PAINT GREEN (-625 3325);
DISPLAY INVISIBLE (-625 3325);
FORCEPROP 1 LAST COMMENT_BODY TRUE
J 0
(-995 3355);
DISPLAY 0.872340 (-995 3355);
PAINT GREEN (-995 3355);
DISPLAY INVISIBLE (-995 3355);
FORCEADD OFFPAGE..4
(-950 3350);
FORCEPROP 2 LAST $XR0 270 
J 0
(-764 3350);
DISPLAY 0.638298 (-764 3350);
PAINT MONO (-764 3350);
FORCEPROP 2 LAST PATH I107
J 0
(-750 3400);
DISPLAY 1.021277 (-750 3400);
DISPLAY INVISIBLE (-750 3400);
FORCEPROP 2 LAST CDS_LIB standard
J 0
(-950 3350);
DISPLAY INVISIBLE (-950 3350);
FORCEPROP 1 LAST OFFPAGE TRUE
J 0
(-625 3225);
DISPLAY 0.872340 (-625 3225);
PAINT GREEN (-625 3225);
DISPLAY INVISIBLE (-625 3225);
FORCEPROP 1 LAST COMMENT_BODY TRUE
J 0
(-975 3250);
DISPLAY 0.872340 (-975 3250);
PAINT GREEN (-975 3250);
DISPLAY INVISIBLE (-975 3250);
FORCEADD OFFPAGE..2
(-950 3150);
FORCEPROP 2 LAST $XR0 272 
J 0
(-761 3150);
DISPLAY 0.638298 (-761 3150);
PAINT MONO (-761 3150);
FORCEPROP 2 LAST PATH I108
J 0
(-750 3200);
DISPLAY 1.021277 (-750 3200);
DISPLAY INVISIBLE (-750 3200);
FORCEPROP 2 LAST CDS_LIB standard
J 0
(-950 3150);
DISPLAY INVISIBLE (-950 3150);
FORCEPROP 1 LAST OFFPAGE TRUE
J 0
(-625 3025);
DISPLAY 0.872340 (-625 3025);
PAINT GREEN (-625 3025);
DISPLAY INVISIBLE (-625 3025);
FORCEPROP 1 LAST COMMENT_BODY TRUE
J 0
(-995 3055);
DISPLAY 0.872340 (-995 3055);
PAINT GREEN (-995 3055);
DISPLAY INVISIBLE (-995 3055);
FORCEADD OFFPAGE..4
(-950 3050);
FORCEPROP 2 LAST $XR0 272 
J 0
(-764 3050);
DISPLAY 0.638298 (-764 3050);
PAINT MONO (-764 3050);
FORCEPROP 2 LAST PATH I109
J 0
(-750 3100);
DISPLAY 1.021277 (-750 3100);
DISPLAY INVISIBLE (-750 3100);
FORCEPROP 2 LAST CDS_LIB standard
J 0
(-950 3050);
DISPLAY INVISIBLE (-950 3050);
FORCEPROP 1 LAST OFFPAGE TRUE
J 0
(-625 2925);
DISPLAY 0.872340 (-625 2925);
PAINT GREEN (-625 2925);
DISPLAY INVISIBLE (-625 2925);
FORCEPROP 1 LAST COMMENT_BODY TRUE
J 0
(-975 2950);
DISPLAY 0.872340 (-975 2950);
PAINT GREEN (-975 2950);
DISPLAY INVISIBLE (-975 2950);
FORCEADD Q_RES..1
(-5200 1200);
FORCEPROP 1 LAST PART_NUMBER CS00002JB13
J 0
(-5075 1150);
DISPLAY 0.510638 (-5075 1150);
PAINT BLUE (-5075 1150);
DISPLAY INVISIBLE (-5075 1150);
FORCEPROP 1 LAST TOLERANCE 5%
J 0
(-5025 1200);
DISPLAY 0.617021 (-5025 1200);
PAINT SKYBLUE (-5025 1200);
FORCEPROP 1 LAST MATERIAL EMPTY
J 0
(-4725 1200);
DISPLAY 0.617021 (-4725 1200);
PAINT RED (-4725 1200);
FORCEPROP 1 LAST VALUE 0
J 2
(-5050 1200);
DISPLAY 0.617021 (-5050 1200);
PAINT SKYBLUE (-5050 1200);
FORCEPROP 1 LAST PACK_TYPE 0402LF
J 0
(-4950 1200);
DISPLAY 0.617021 (-4950 1200);
PAINT SKYBLUE (-4950 1200);
FORCEPROP 1 LAST LOCATION PR157
J 0
(-5425 1200);
DISPLAY 0.617021 (-5425 1200);
PAINT AQUA (-5425 1200);
FORCEPROP 1 LASTPIN (-5300 1200) $PN 1
J 0
(-5288 1212);
DISPLAY 0.617021 (-5288 1212);
PAINT MONO (-5288 1212);
FORCEPROP 1 LASTPIN (-5100 1200) $PN 2
J 0
(-5138 1212);
DISPLAY 0.617021 (-5138 1212);
PAINT MONO (-5138 1212);
FORCEPROP 1 LAST PATH I11
J 0
(-5250 1350);
DISPLAY 0.978723 (-5250 1350);
PAINT WHITE (-5250 1350);
DISPLAY INVISIBLE (-5250 1350);
FORCEPROP 1 LAST WATTAGE 1/16W
J 2
(-4825 1100);
DISPLAY 0.510638 (-4825 1100);
PAINT SKYBLUE (-4825 1100);
DISPLAY INVISIBLE (-4825 1100);
FORCEPROP 2 LAST CDS_LIB pure_quanta
J 0
(-5200 1200);
DISPLAY INVISIBLE (-5200 1200);
FORCEPROP 1 LAST LOCATION PR157
J 0
(-5250 1300);
DISPLAY 1.021277 (-5250 1300);
PAINT AQUA (-5250 1300);
DISPLAY INVISIBLE (-5250 1300);
FORCEPROP 0 LAST $SEC 1
J 0
(-5250 1300);
DISPLAY 0.680851 (-5250 1300);
PAINT MONO (-5250 1300);
DISPLAY INVISIBLE (-5250 1300);
FORCEPROP 0 LAST CDS_SEC 1
J 0
(-5250 1300);
DISPLAY 1.021277 (-5250 1300);
DISPLAY INVISIBLE (-5250 1300);
FORCEADD OFFPAGE..2
(-950 2850);
FORCEPROP 2 LAST $XR0 272 
J 0
(-761 2850);
DISPLAY 0.638298 (-761 2850);
PAINT MONO (-761 2850);
FORCEPROP 2 LAST PATH I110
J 0
(-750 2900);
DISPLAY 1.021277 (-750 2900);
DISPLAY INVISIBLE (-750 2900);
FORCEPROP 2 LAST CDS_LIB standard
J 0
(-950 2850);
DISPLAY INVISIBLE (-950 2850);
FORCEPROP 1 LAST OFFPAGE TRUE
J 0
(-625 2725);
DISPLAY 0.872340 (-625 2725);
PAINT GREEN (-625 2725);
DISPLAY INVISIBLE (-625 2725);
FORCEPROP 1 LAST COMMENT_BODY TRUE
J 0
(-995 2755);
DISPLAY 0.872340 (-995 2755);
PAINT GREEN (-995 2755);
DISPLAY INVISIBLE (-995 2755);
FORCEADD OFFPAGE..4
(-950 2750);
FORCEPROP 2 LAST $XR0 272 
J 0
(-764 2750);
DISPLAY 0.638298 (-764 2750);
PAINT MONO (-764 2750);
FORCEPROP 2 LAST PATH I111
J 0
(-750 2800);
DISPLAY 1.021277 (-750 2800);
DISPLAY INVISIBLE (-750 2800);
FORCEPROP 2 LAST CDS_LIB standard
J 0
(-950 2750);
DISPLAY INVISIBLE (-950 2750);
FORCEPROP 1 LAST OFFPAGE TRUE
J 0
(-625 2625);
DISPLAY 0.872340 (-625 2625);
PAINT GREEN (-625 2625);
DISPLAY INVISIBLE (-625 2625);
FORCEPROP 1 LAST COMMENT_BODY TRUE
J 0
(-975 2650);
DISPLAY 0.872340 (-975 2650);
PAINT GREEN (-975 2650);
DISPLAY INVISIBLE (-975 2650);
FORCEADD OFFPAGE..2
(-950 2550);
FORCEPROP 2 LAST $XR0 271 
J 0
(-761 2550);
DISPLAY 0.638298 (-761 2550);
PAINT MONO (-761 2550);
FORCEPROP 2 LAST PATH I112
J 0
(-750 2600);
DISPLAY 1.021277 (-750 2600);
DISPLAY INVISIBLE (-750 2600);
FORCEPROP 2 LAST CDS_LIB standard
J 0
(-950 2550);
DISPLAY INVISIBLE (-950 2550);
FORCEPROP 1 LAST OFFPAGE TRUE
J 0
(-625 2425);
DISPLAY 0.872340 (-625 2425);
PAINT GREEN (-625 2425);
DISPLAY INVISIBLE (-625 2425);
FORCEPROP 1 LAST COMMENT_BODY TRUE
J 0
(-995 2455);
DISPLAY 0.872340 (-995 2455);
PAINT GREEN (-995 2455);
DISPLAY INVISIBLE (-995 2455);
FORCEADD OFFPAGE..4
(-950 2450);
FORCEPROP 2 LAST $XR0 271 
J 0
(-764 2450);
DISPLAY 0.638298 (-764 2450);
PAINT MONO (-764 2450);
FORCEPROP 2 LAST PATH I113
J 0
(-750 2500);
DISPLAY 1.021277 (-750 2500);
DISPLAY INVISIBLE (-750 2500);
FORCEPROP 2 LAST CDS_LIB standard
J 0
(-950 2450);
DISPLAY INVISIBLE (-950 2450);
FORCEPROP 1 LAST OFFPAGE TRUE
J 0
(-625 2325);
DISPLAY 0.872340 (-625 2325);
PAINT GREEN (-625 2325);
DISPLAY INVISIBLE (-625 2325);
FORCEPROP 1 LAST COMMENT_BODY TRUE
J 0
(-975 2350);
DISPLAY 0.872340 (-975 2350);
PAINT GREEN (-975 2350);
DISPLAY INVISIBLE (-975 2350);
FORCEADD UNIVERSAL_GND..1
(-125 1200);
FORCEPROP 3 LASTPIN (-125 1250) SIG_NAME GND\g
J 0
(-115 1260);
DISPLAY 0.659574 (-115 1260);
PAINT MONO (-115 1260);
DISPLAY INVISIBLE (-115 1260);
FORCEPROP 1 LAST PATH I114
J 0
(-50 1200);
DISPLAY 0.872340 (-50 1200);
PAINT AQUA (-50 1200);
DISPLAY INVISIBLE (-50 1200);
FORCEPROP 2 LAST CDS_LIB logical_power
J 0
(-125 1200);
DISPLAY INVISIBLE (-125 1200);
FORCEPROP 1 LAST HDL_POWER GND
J 1
(-100 1125);
DISPLAY 0.872340 (-100 1125);
PAINT GREEN (-100 1125);
DISPLAY INVISIBLE (-100 1125);
FORCEADD OFFPAGE..4
(-900 1350);
FORCEPROP 2 LAST $XR3 270 
J 0
(-354 1350);
DISPLAY 0.638298 (-354 1350);
PAINT MONO (-354 1350);
FORCEPROP 2 LAST $XR2 269 
J 0
(-474 1350);
DISPLAY 0.638298 (-474 1350);
PAINT MONO (-474 1350);
FORCEPROP 2 LAST $XR1 268 
J 0
(-594 1350);
DISPLAY 0.638298 (-594 1350);
PAINT MONO (-594 1350);
FORCEPROP 2 LAST $XR0 267 
J 0
(-714 1350);
DISPLAY 0.638298 (-714 1350);
PAINT MONO (-714 1350);
FORCEPROP 2 LAST PATH I115
J 0
(-350 1400);
DISPLAY 1.021277 (-350 1400);
DISPLAY INVISIBLE (-350 1400);
FORCEPROP 2 LAST CDS_LIB standard
J 0
(-900 1350);
DISPLAY INVISIBLE (-900 1350);
FORCEPROP 1 LAST OFFPAGE TRUE
J 0
(-575 1225);
DISPLAY 0.872340 (-575 1225);
PAINT GREEN (-575 1225);
DISPLAY INVISIBLE (-575 1225);
FORCEPROP 1 LAST COMMENT_BODY TRUE
J 0
(-925 1250);
DISPLAY 0.872340 (-925 1250);
PAINT GREEN (-925 1250);
DISPLAY INVISIBLE (-925 1250);
FORCEADD Q_CAP..1
(-125 1450);
FORCEPROP 1 LAST PART_NUMBER TMP_QCH14706KB18
J 0
(-75 1250);
DISPLAY 0.617021 (-75 1250);
PAINT BLUE (-75 1250);
DISPLAY INVISIBLE (-75 1250);
FORCEPROP 1 LAST VALUE 470PF
J 0
(-75 1500);
DISPLAY 0.617021 (-75 1500);
PAINT SKYBLUE (-75 1500);
FORCEPROP 1 LAST PACK_TYPE 0402
J 0
(-75 1300);
DISPLAY 0.617021 (-75 1300);
PAINT SKYBLUE (-75 1300);
FORCEPROP 1 LAST MATERIAL X7R
J 0
(-75 1350);
DISPLAY 0.617021 (-75 1350);
PAINT SKYBLUE (-75 1350);
FORCEPROP 1 LAST VOLTAGE 50V
J 0
(-75 1450);
DISPLAY 0.617021 (-75 1450);
PAINT SKYBLUE (-75 1450);
FORCEPROP 1 LAST TOLERANCE 10%
J 0
(-75 1400);
DISPLAY 0.617021 (-75 1400);
PAINT SKYBLUE (-75 1400);
FORCEPROP 1 LAST LOCATION PC100
J 0
(-75 1550);
DISPLAY 0.617021 (-75 1550);
PAINT AQUA (-75 1550);
FORCEPROP 1 LASTPIN (-125 1550) $PN 1
J 0
(-115 1530);
DISPLAY 0.787234 (-115 1530);
PAINT MONO (-115 1530);
FORCEPROP 1 LASTPIN (-125 1350) $PN 2
J 0
(-115 1330);
DISPLAY 0.787234 (-115 1330);
PAINT MONO (-115 1330);
FORCEPROP 1 LAST PATH I116
J 0
(-75 1600);
DISPLAY 0.978723 (-75 1600);
PAINT WHITE (-75 1600);
DISPLAY INVISIBLE (-75 1600);
FORCEPROP 2 LAST CDS_LIB pure_quanta
J 0
(-125 1450);
DISPLAY INVISIBLE (-125 1450);
FORCEPROP 1 LAST LOCATION PC100
J 0
(-75 1600);
DISPLAY 1.021277 (-75 1600);
PAINT AQUA (-75 1600);
DISPLAY INVISIBLE (-75 1600);
FORCEPROP 0 LAST $SEC 1
J 0
(-75 1600);
DISPLAY 0.680851 (-75 1600);
PAINT MONO (-75 1600);
DISPLAY INVISIBLE (-75 1600);
FORCEPROP 0 LAST CDS_SEC 1
J 0
(-75 1600);
DISPLAY 1.021277 (-75 1600);
DISPLAY INVISIBLE (-75 1600);
FORCEADD OFFPAGE..1
(75 1900);
FORCEPROP 2 LAST $XR2 274 
J 0
(-386 1900);
DISPLAY 0.638298 (-386 1900);
PAINT MONO (-386 1900);
FORCEPROP 2 LAST $XR1 266 
J 0
(-266 1900);
DISPLAY 0.638298 (-266 1900);
PAINT MONO (-266 1900);
FORCEPROP 2 LAST $XR0 14 
J 0
(-146 1900);
DISPLAY 0.638298 (-146 1900);
PAINT MONO (-146 1900);
FORCEPROP 2 LAST PATH I117
J 0
(-125 1950);
DISPLAY 1.021277 (-125 1950);
DISPLAY INVISIBLE (-125 1950);
FORCEPROP 2 LAST CDS_LIB standard
J 0
(75 1900);
PAINT MONO (75 1900);
DISPLAY INVISIBLE (75 1900);
FORCEPROP 1 LAST OFFPAGE TRUE
J 0
(400 1775);
DISPLAY 0.872340 (400 1775);
PAINT GREEN (400 1775);
DISPLAY INVISIBLE (400 1775);
FORCEPROP 1 LAST COMMENT_BODY TRUE
J 0
(200 1800);
DISPLAY 0.872340 (200 1800);
PAINT GREEN (200 1800);
DISPLAY INVISIBLE (200 1800);
FORCEADD OFFPAGE..1
(75 2050);
FORCEPROP 2 LAST $XR2 274 
J 0
(-386 2050);
DISPLAY 0.638298 (-386 2050);
PAINT MONO (-386 2050);
FORCEPROP 2 LAST $XR1 266 
J 0
(-266 2050);
DISPLAY 0.638298 (-266 2050);
PAINT MONO (-266 2050);
FORCEPROP 2 LAST $XR0 14 
J 0
(-146 2050);
DISPLAY 0.638298 (-146 2050);
PAINT MONO (-146 2050);
FORCEPROP 2 LAST PATH I118
J 0
(-125 2100);
DISPLAY 1.021277 (-125 2100);
DISPLAY INVISIBLE (-125 2100);
FORCEPROP 2 LAST CDS_LIB standard
J 0
(75 2050);
PAINT MONO (75 2050);
DISPLAY INVISIBLE (75 2050);
FORCEPROP 1 LAST OFFPAGE TRUE
J 0
(400 1925);
DISPLAY 0.872340 (400 1925);
PAINT GREEN (400 1925);
DISPLAY INVISIBLE (400 1925);
FORCEPROP 1 LAST COMMENT_BODY TRUE
J 0
(200 1950);
DISPLAY 0.872340 (200 1950);
PAINT GREEN (200 1950);
DISPLAY INVISIBLE (200 1950);
FORCEADD OFFPAGE..1
(75 2200);
FORCEPROP 2 LAST $XR2 274 
J 0
(-386 2200);
DISPLAY 0.638298 (-386 2200);
PAINT MONO (-386 2200);
FORCEPROP 2 LAST $XR1 266 
J 0
(-266 2200);
DISPLAY 0.638298 (-266 2200);
PAINT MONO (-266 2200);
FORCEPROP 2 LAST $XR0 14 
J 0
(-146 2200);
DISPLAY 0.638298 (-146 2200);
PAINT MONO (-146 2200);
FORCEPROP 2 LAST PATH I119
J 0
(-125 2250);
DISPLAY 1.021277 (-125 2250);
DISPLAY INVISIBLE (-125 2250);
FORCEPROP 2 LAST CDS_LIB standard
J 0
(75 2200);
PAINT MONO (75 2200);
DISPLAY INVISIBLE (75 2200);
FORCEPROP 1 LAST OFFPAGE TRUE
J 0
(400 2075);
DISPLAY 0.872340 (400 2075);
PAINT GREEN (400 2075);
DISPLAY INVISIBLE (400 2075);
FORCEPROP 1 LAST COMMENT_BODY TRUE
J 0
(200 2100);
DISPLAY 0.872340 (200 2100);
PAINT GREEN (200 2100);
DISPLAY INVISIBLE (200 2100);
FORCEADD VCC15..1
(-5475 1325);
FORCEPROP 3 LASTPIN (-5475 1275) SIG_NAME P12V_AUX\g
J 0
(-5465 1285);
DISPLAY 0.659574 (-5465 1285);
PAINT MONO (-5465 1285);
DISPLAY INVISIBLE (-5465 1285);
FORCEPROP 1 LAST HDL_POWER P12V_AUX
J 1
(-5475 1375);
DISPLAY 0.617021 (-5475 1375);
PAINT GREEN (-5475 1375);
FORCEPROP 1 LAST PATH I12
J 0
(-5425 1350);
DISPLAY 0.872340 (-5425 1350);
PAINT AQUA (-5425 1350);
DISPLAY INVISIBLE (-5425 1350);
FORCEPROP 2 LAST CDS_LIB logical_power
J 0
(-5475 1325);
DISPLAY INVISIBLE (-5475 1325);
FORCEADD UNIVERSAL_GND..1
(550 1175);
FORCEPROP 3 LASTPIN (550 1225) SIG_NAME GND\g
J 0
(560 1235);
DISPLAY 0.659574 (560 1235);
PAINT MONO (560 1235);
DISPLAY INVISIBLE (560 1235);
FORCEPROP 1 LAST PATH I120
J 0
(625 1175);
DISPLAY 0.872340 (625 1175);
PAINT AQUA (625 1175);
DISPLAY INVISIBLE (625 1175);
FORCEPROP 2 LAST CDS_LIB logical_power
J 0
(550 1175);
PAINT MONO (550 1175);
DISPLAY INVISIBLE (550 1175);
FORCEPROP 1 LAST HDL_POWER GND
J 1
(575 1100);
DISPLAY 0.872340 (575 1100);
PAINT GREEN (575 1100);
DISPLAY INVISIBLE (575 1100);
FORCEADD Q_RES..2
(550 1425);
FORCEPROP 1 LAST PART_NUMBER CS31002FB08
J 0
(590 1300);
DISPLAY 0.638298 (590 1300);
DISPLAY INVISIBLE (590 1300);
FORCEPROP 1 LAST MATERIAL EMPTY
J 0
(590 1350);
DISPLAY 0.638298 (590 1350);
PAINT RED (590 1350);
FORCEPROP 1 LAST WATTAGE 1/16W
J 0
(590 1400);
DISPLAY 0.638298 (590 1400);
FORCEPROP 1 LAST TOLERANCE 1%
J 0
(595 1450);
DISPLAY 0.638298 (595 1450);
FORCEPROP 1 LAST VALUE 10K
J 0
(595 1500);
DISPLAY 0.638298 (595 1500);
FORCEPROP 1 LAST PACK_TYPE 0402LF
J 0
(590 1250);
DISPLAY 0.638298 (590 1250);
FORCEPROP 1 LAST LOCATION PR451
J 0
(595 1550);
DISPLAY 0.638298 (595 1550);
FORCEPROP 1 LASTPIN (550 1525) $PN 1
J 0
(555 1487);
DISPLAY 0.787234 (555 1487);
PAINT MONO (555 1487);
FORCEPROP 1 LASTPIN (550 1325) $PN 2
J 0
(555 1335);
DISPLAY 0.787234 (555 1335);
PAINT MONO (555 1335);
FORCEPROP 1 LAST PATH I121
J 0
(600 1600);
DISPLAY 0.978723 (600 1600);
PAINT WHITE (600 1600);
DISPLAY INVISIBLE (600 1600);
FORCEPROP 2 LAST CDS_LIB pure_quanta
J 0
(550 1425);
DISPLAY INVISIBLE (550 1425);
FORCEPROP 0 LAST $SEC 1
J 0
(600 1600);
DISPLAY 0.680851 (600 1600);
PAINT MONO (600 1600);
DISPLAY INVISIBLE (600 1600);
FORCEPROP 0 LAST CDS_SEC 1
J 0
(275 1500);
DISPLAY INVISIBLE (275 1500);
FORCEADD OFFPAGE..4
(975 1650);
FORCEPROP 2 LAST $XR1 272 
J 0
(1281 1650);
DISPLAY 0.638298 (1281 1650);
PAINT MONO (1281 1650);
FORCEPROP 2 LAST $XR0 271 
J 0
(1161 1650);
DISPLAY 0.638298 (1161 1650);
PAINT MONO (1161 1650);
FORCEPROP 2 LAST PATH I122
J 0
(1300 1700);
DISPLAY 1.021277 (1300 1700);
DISPLAY INVISIBLE (1300 1700);
FORCEPROP 2 LAST CDS_LIB standard
J 0
(975 1650);
PAINT MONO (975 1650);
DISPLAY INVISIBLE (975 1650);
FORCEPROP 1 LAST OFFPAGE TRUE
J 0
(1300 1525);
DISPLAY 0.872340 (1300 1525);
PAINT GREEN (1300 1525);
DISPLAY INVISIBLE (1300 1525);
FORCEPROP 1 LAST COMMENT_BODY TRUE
J 0
(950 1550);
DISPLAY 0.872340 (950 1550);
PAINT GREEN (950 1550);
DISPLAY INVISIBLE (950 1550);
FORCEADD Q_RES..1
(950 1900);
FORCEPROP 1 LAST PART_NUMBER CS04992FB07
J 0
(1075 1950);
DISPLAY 0.617021 (1075 1950);
PAINT BLUE (1075 1950);
DISPLAY INVISIBLE (1075 1950);
FORCEPROP 1 LAST TOLERANCE 1%
J 0
(1225 1900);
DISPLAY 0.617021 (1225 1900);
PAINT SKYBLUE (1225 1900);
FORCEPROP 1 LAST MATERIAL EMPTY
J 0
(1325 1900);
DISPLAY 0.617021 (1325 1900);
PAINT RED (1325 1900);
FORCEPROP 1 LAST WATTAGE 1/16W
J 2
(1425 2000);
DISPLAY 0.617021 (1425 2000);
PAINT SKYBLUE (1425 2000);
FORCEPROP 1 LAST PACK_TYPE 0402LF
J 0
(1075 2000);
DISPLAY 0.617021 (1075 2000);
PAINT SKYBLUE (1075 2000);
FORCEPROP 1 LAST VALUE 49.9
J 2
(1200 1900);
DISPLAY 0.617021 (1200 1900);
PAINT SKYBLUE (1200 1900);
FORCEPROP 1 LAST LOCATION R2382
J 0
(700 1900);
DISPLAY 0.617021 (700 1900);
PAINT AQUA (700 1900);
FORCEPROP 1 LASTPIN (850 1900) $PN 1
J 0
(862 1912);
DISPLAY 0.617021 (862 1912);
FORCEPROP 1 LASTPIN (1050 1900) $PN 2
J 0
(1012 1912);
DISPLAY 0.617021 (1012 1912);
FORCEPROP 1 LAST PATH I123
J 0
(900 2050);
DISPLAY 0.978723 (900 2050);
PAINT WHITE (900 2050);
DISPLAY INVISIBLE (900 2050);
FORCEPROP 2 LAST CDS_LIB pure_quanta
J 0
(950 1900);
PAINT MONO (950 1900);
DISPLAY INVISIBLE (950 1900);
FORCEPROP 2 LAST $SEC 1
J 0
(900 2100);
DISPLAY 0.680851 (900 2100);
PAINT MONO (900 2100);
DISPLAY INVISIBLE (900 2100);
FORCEPROP 2 LAST CDS_SEC 1
J 0
(900 2100);
DISPLAY 1.021277 (900 2100);
DISPLAY INVISIBLE (900 2100);
FORCEADD Q_RES..1
(950 2200);
FORCEPROP 1 LAST PART_NUMBER CS11002FB07
J 0
(1075 2250);
DISPLAY 0.489362 (1075 2250);
PAINT BLUE (1075 2250);
DISPLAY INVISIBLE (1075 2250);
FORCEPROP 1 LAST PACK_TYPE 0402LF
J 0
(1250 2200);
DISPLAY 0.489362 (1250 2200);
PAINT SKYBLUE (1250 2200);
FORCEPROP 1 LAST WATTAGE 1/16W
J 2
(1325 2300);
DISPLAY 0.489362 (1325 2300);
PAINT SKYBLUE (1325 2300);
FORCEPROP 1 LAST TOLERANCE 1%
J 0
(1175 2200);
DISPLAY 0.489362 (1175 2200);
PAINT SKYBLUE (1175 2200);
FORCEPROP 1 LAST MATERIAL CHIP
J 0
(1075 2300);
DISPLAY 0.489362 (1075 2300);
PAINT SKYBLUE (1075 2300);
FORCEPROP 1 LAST VALUE 100
J 2
(1150 2200);
DISPLAY 0.489362 (1150 2200);
PAINT SKYBLUE (1150 2200);
FORCEPROP 1 LAST LOCATION R2590
J 0
(750 2200);
DISPLAY 0.617021 (750 2200);
PAINT AQUA (750 2200);
FORCEPROP 1 LASTPIN (850 2200) $PN 1
J 0
(862 2212);
DISPLAY 0.787234 (862 2212);
PAINT MONO (862 2212);
FORCEPROP 1 LASTPIN (1050 2200) $PN 2
J 0
(1012 2212);
DISPLAY 0.787234 (1012 2212);
PAINT MONO (1012 2212);
FORCEPROP 1 LAST PATH I124
J 0
(900 2350);
DISPLAY 0.978723 (900 2350);
PAINT WHITE (900 2350);
DISPLAY INVISIBLE (900 2350);
FORCEPROP 2 LAST CDS_LIB pure_quanta
J 0
(950 2200);
DISPLAY INVISIBLE (950 2200);
FORCEPROP 0 LAST $SEC 1
J 0
(1325 2325);
DISPLAY 0.680851 (1325 2325);
PAINT MONO (1325 2325);
DISPLAY INVISIBLE (1325 2325);
FORCEPROP 0 LAST CDS_SEC 1
J 0
(1325 2325);
DISPLAY 1.021277 (1325 2325);
DISPLAY INVISIBLE (1325 2325);
FORCEADD Q_RES..1
(950 2050);
FORCEPROP 1 LAST PART_NUMBER CS04992FB07
J 0
(1075 2100);
DISPLAY 0.617021 (1075 2100);
PAINT BLUE (1075 2100);
DISPLAY INVISIBLE (1075 2100);
FORCEPROP 1 LAST VALUE 49.9
J 2
(1200 2050);
DISPLAY 0.617021 (1200 2050);
PAINT SKYBLUE (1200 2050);
FORCEPROP 1 LAST TOLERANCE 1%
J 0
(1225 2050);
DISPLAY 0.617021 (1225 2050);
PAINT SKYBLUE (1225 2050);
FORCEPROP 1 LAST MATERIAL CHIP
J 0
(1325 2050);
DISPLAY 0.617021 (1325 2050);
PAINT SKYBLUE (1325 2050);
FORCEPROP 1 LAST WATTAGE 1/16W
J 2
(1425 2150);
DISPLAY 0.617021 (1425 2150);
PAINT SKYBLUE (1425 2150);
FORCEPROP 1 LAST PACK_TYPE 0402LF
J 0
(1075 2150);
DISPLAY 0.617021 (1075 2150);
PAINT SKYBLUE (1075 2150);
FORCEPROP 1 LAST LOCATION R2381
J 0
(700 2050);
DISPLAY 0.617021 (700 2050);
PAINT AQUA (700 2050);
FORCEPROP 1 LASTPIN (850 2050) $PN 1
J 0
(862 2062);
DISPLAY 0.617021 (862 2062);
FORCEPROP 1 LASTPIN (1050 2050) $PN 2
J 0
(1012 2062);
DISPLAY 0.617021 (1012 2062);
FORCEPROP 1 LAST PATH I125
J 0
(900 2200);
DISPLAY 0.978723 (900 2200);
PAINT WHITE (900 2200);
DISPLAY INVISIBLE (900 2200);
FORCEPROP 2 LAST CDS_LIB pure_quanta
J 0
(950 2050);
PAINT MONO (950 2050);
DISPLAY INVISIBLE (950 2050);
FORCEPROP 2 LAST $SEC 1
J 0
(900 2250);
DISPLAY 0.680851 (900 2250);
PAINT MONO (900 2250);
DISPLAY INVISIBLE (900 2250);
FORCEPROP 2 LAST CDS_SEC 1
J 0
(900 2250);
DISPLAY 1.021277 (900 2250);
DISPLAY INVISIBLE (900 2250);
FORCEADD UNIVERSAL_GND..1
(750 2375);
FORCEPROP 3 LASTPIN (750 2425) SIG_NAME GND\g
J 0
(760 2435);
DISPLAY 0.659574 (760 2435);
PAINT MONO (760 2435);
DISPLAY INVISIBLE (760 2435);
FORCEPROP 1 LAST PATH I126
J 0
(825 2375);
DISPLAY 0.872340 (825 2375);
PAINT AQUA (825 2375);
DISPLAY INVISIBLE (825 2375);
FORCEPROP 2 LAST CDS_LIB logical_power
J 0
(750 2375);
PAINT MONO (750 2375);
DISPLAY INVISIBLE (750 2375);
FORCEPROP 1 LAST HDL_POWER GND
J 1
(775 2300);
DISPLAY 0.872340 (775 2300);
PAINT GREEN (775 2300);
DISPLAY INVISIBLE (775 2300);
FORCEADD Q_CAP..1
(750 2675);
FORCEPROP 1 LAST PART_NUMBER CH610KME907
J 0
(800 2475);
DISPLAY 0.617021 (800 2475);
PAINT BLUE (800 2475);
DISPLAY INVISIBLE (800 2475);
FORCEPROP 1 LAST VALUE 10UF
J 0
(800 2725);
DISPLAY 0.617021 (800 2725);
PAINT SKYBLUE (800 2725);
FORCEPROP 1 LAST VOLTAGE 4V
J 0
(800 2675);
DISPLAY 0.617021 (800 2675);
PAINT SKYBLUE (800 2675);
FORCEPROP 1 LAST TOLERANCE 20%
J 0
(800 2625);
DISPLAY 0.617021 (800 2625);
PAINT SKYBLUE (800 2625);
FORCEPROP 1 LAST MATERIAL EMPTY
J 0
(800 2575);
DISPLAY 0.617021 (800 2575);
PAINT RED (800 2575);
FORCEPROP 1 LAST PACK_TYPE C0603
J 0
(800 2525);
DISPLAY 0.617021 (800 2525);
PAINT SKYBLUE (800 2525);
FORCEPROP 1 LAST LOCATION C3270
J 0
(800 2775);
DISPLAY 0.617021 (800 2775);
PAINT AQUA (800 2775);
FORCEPROP 1 LASTPIN (750 2775) $PN 1
J 0
(760 2755);
DISPLAY 0.617021 (760 2755);
PAINT MONO (760 2755);
FORCEPROP 1 LASTPIN (750 2575) $PN 2
J 0
(760 2555);
DISPLAY 0.617021 (760 2555);
PAINT MONO (760 2555);
FORCEPROP 1 LAST PATH I127
J 0
(800 2825);
DISPLAY 0.978723 (800 2825);
PAINT WHITE (800 2825);
DISPLAY INVISIBLE (800 2825);
FORCEPROP 2 LAST CDS_LIB pure_quanta
J 0
(750 2675);
DISPLAY INVISIBLE (750 2675);
FORCEPROP 1 LAST LOCATION C3270
J 0
(800 2825);
DISPLAY 1.021277 (800 2825);
PAINT AQUA (800 2825);
DISPLAY INVISIBLE (800 2825);
FORCEPROP 0 LAST $SEC 1
J 0
(800 2825);
DISPLAY 0.680851 (800 2825);
PAINT MONO (800 2825);
DISPLAY INVISIBLE (800 2825);
FORCEPROP 0 LAST CDS_SEC 1
J 0
(800 2825);
DISPLAY 1.021277 (800 2825);
DISPLAY INVISIBLE (800 2825);
FORCEADD Q_CAP..1
(1075 2650);
FORCEPROP 1 LAST PART_NUMBER CH4106K1B01
J 0
(1150 2475);
DISPLAY 0.617021 (1150 2475);
PAINT BLUE (1150 2475);
DISPLAY INVISIBLE (1150 2475);
FORCEPROP 1 LAST VALUE 100NF
J 0
(1150 2725);
DISPLAY 0.617021 (1150 2725);
PAINT SKYBLUE (1150 2725);
FORCEPROP 1 LAST VOLTAGE 50V
J 0
(1150 2675);
DISPLAY 0.617021 (1150 2675);
PAINT SKYBLUE (1150 2675);
FORCEPROP 1 LAST PACK_TYPE C0402
J 0
(1150 2525);
DISPLAY 0.617021 (1150 2525);
PAINT SKYBLUE (1150 2525);
FORCEPROP 1 LAST MATERIAL X7R
J 0
(1150 2575);
DISPLAY 0.617021 (1150 2575);
PAINT SKYBLUE (1150 2575);
FORCEPROP 1 LAST TOLERANCE 10%
J 0
(1150 2625);
DISPLAY 0.617021 (1150 2625);
PAINT SKYBLUE (1150 2625);
FORCEPROP 1 LAST LOCATION C3271
J 0
(1150 2775);
DISPLAY 0.617021 (1150 2775);
PAINT AQUA (1150 2775);
FORCEPROP 1 LASTPIN (1075 2750) $PN 1
J 0
(1085 2730);
DISPLAY 0.617021 (1085 2730);
PAINT MONO (1085 2730);
FORCEPROP 1 LASTPIN (1075 2550) $PN 2
J 0
(1085 2530);
DISPLAY 0.617021 (1085 2530);
PAINT MONO (1085 2530);
FORCEPROP 1 LAST PATH I128
J 0
(1125 2800);
DISPLAY 0.978723 (1125 2800);
PAINT WHITE (1125 2800);
DISPLAY INVISIBLE (1125 2800);
FORCEPROP 2 LAST CDS_LIB pure_quanta
J 0
(1075 2650);
DISPLAY INVISIBLE (1075 2650);
FORCEPROP 1 LAST LOCATION C3271
J 0
(1125 2850);
DISPLAY 1.021277 (1125 2850);
PAINT AQUA (1125 2850);
DISPLAY INVISIBLE (1125 2850);
FORCEPROP 0 LAST $SEC 1
J 0
(1125 2850);
DISPLAY 0.680851 (1125 2850);
PAINT MONO (1125 2850);
DISPLAY INVISIBLE (1125 2850);
FORCEPROP 0 LAST CDS_SEC 1
J 0
(1125 2850);
DISPLAY 1.021277 (1125 2850);
DISPLAY INVISIBLE (1125 2850);
FORCEADD VCC15..1
(1475 2950);
FORCEPROP 3 LASTPIN (1475 2900) SIG_NAME PVNN_TERM_CPU0\g
J 0
(1485 2910);
DISPLAY 0.659574 (1485 2910);
PAINT MONO (1485 2910);
DISPLAY INVISIBLE (1485 2910);
FORCEPROP 1 LAST HDL_POWER PVNN_TERM_CPU0
J 1
(1475 3000);
DISPLAY 0.617021 (1475 3000);
PAINT GREEN (1475 3000);
FORCEPROP 1 LAST PATH I129
J 0
(1525 2975);
DISPLAY 0.872340 (1525 2975);
PAINT AQUA (1525 2975);
DISPLAY INVISIBLE (1525 2975);
FORCEPROP 2 LAST CDS_LIB logical_power
J 0
(1475 2950);
DISPLAY INVISIBLE (1475 2950);
FORCEADD VCC15..1
(-5425 2000);
FORCEPROP 3 LASTPIN (-5425 1950) SIG_NAME P3V3_AUX\g
J 0
(-5415 1960);
DISPLAY 0.659574 (-5415 1960);
PAINT MONO (-5415 1960);
DISPLAY INVISIBLE (-5415 1960);
FORCEPROP 1 LAST HDL_POWER P3V3_AUX
J 1
(-5425 2050);
DISPLAY 0.617021 (-5425 2050);
PAINT GREEN (-5425 2050);
FORCEPROP 1 LAST PATH I13
J 0
(-5375 2025);
DISPLAY 0.872340 (-5375 2025);
PAINT AQUA (-5375 2025);
DISPLAY INVISIBLE (-5375 2025);
FORCEPROP 2 LAST CDS_LIB logical_power
J 0
(-5425 2000);
PAINT MONO (-5425 2000);
DISPLAY INVISIBLE (-5425 2000);
FORCEADD UNIVERSAL_GND..1
R 3
(-650 5675);
FORCEPROP 3 LASTPIN (-700 5675) SIG_NAME GND\g
J 0
(-690 5685);
DISPLAY 0.659574 (-690 5685);
PAINT MONO (-690 5685);
DISPLAY INVISIBLE (-690 5685);
FORCEPROP 1 LAST PATH I130
R 1
J 2
(-650 5600);
DISPLAY 0.872340 (-650 5600);
PAINT AQUA (-650 5600);
DISPLAY INVISIBLE (-650 5600);
FORCEPROP 2 LAST CDS_LIB logical_power
J 0
(-650 5675);
PAINT MONO (-650 5675);
DISPLAY INVISIBLE (-650 5675);
FORCEPROP 1 LAST HDL_POWER GND
R 1
J 1
(-575 5650);
DISPLAY 0.872340 (-575 5650);
PAINT GREEN (-575 5650);
DISPLAY INVISIBLE (-575 5650);
FORCEADD OFFPAGE..2
(-750 6075);
FORCEPROP 2 LAST $XR6 272 
J 0
(-441 6039);
DISPLAY 0.638298 (-441 6039);
PAINT MONO (-441 6039);
FORCEPROP 2 LAST $XR5 271 
J 0
(-561 6039);
DISPLAY 0.638298 (-561 6039);
PAINT MONO (-561 6039);
FORCEPROP 2 LAST $XR4 270 
J 0
(-81 6075);
DISPLAY 0.638298 (-81 6075);
PAINT MONO (-81 6075);
FORCEPROP 2 LAST $XR3 269 
J 0
(-201 6075);
DISPLAY 0.638298 (-201 6075);
PAINT MONO (-201 6075);
FORCEPROP 2 LAST $XR2 268 
J 0
(-321 6075);
DISPLAY 0.638298 (-321 6075);
PAINT MONO (-321 6075);
FORCEPROP 2 LAST $XR1 267 
J 0
(-441 6075);
DISPLAY 0.638298 (-441 6075);
PAINT MONO (-441 6075);
FORCEPROP 2 LAST $XR0 266 
J 0
(-561 6075);
DISPLAY 0.638298 (-561 6075);
PAINT MONO (-561 6075);
FORCEPROP 2 LAST PATH I131
J 0
(-75 6125);
DISPLAY 1.021277 (-75 6125);
DISPLAY INVISIBLE (-75 6125);
FORCEPROP 2 LAST CDS_LIB standard
J 0
(-750 6075);
DISPLAY INVISIBLE (-750 6075);
FORCEPROP 1 LAST OFFPAGE TRUE
J 0
(-425 5950);
DISPLAY 0.872340 (-425 5950);
PAINT GREEN (-425 5950);
DISPLAY INVISIBLE (-425 5950);
FORCEPROP 1 LAST COMMENT_BODY TRUE
J 0
(-795 5980);
DISPLAY 0.872340 (-795 5980);
PAINT GREEN (-795 5980);
DISPLAY INVISIBLE (-795 5980);
FORCEADD UNIVERSAL_GND..1
R 3
(-650 6150);
FORCEPROP 3 LASTPIN (-700 6150) SIG_NAME GND\g
J 0
(-690 6160);
DISPLAY 0.659574 (-690 6160);
PAINT MONO (-690 6160);
DISPLAY INVISIBLE (-690 6160);
FORCEPROP 1 LAST PATH I132
R 1
J 2
(-650 6075);
DISPLAY 0.872340 (-650 6075);
PAINT AQUA (-650 6075);
DISPLAY INVISIBLE (-650 6075);
FORCEPROP 2 LAST CDS_LIB logical_power
J 0
(-650 6150);
PAINT MONO (-650 6150);
DISPLAY INVISIBLE (-650 6150);
FORCEPROP 1 LAST HDL_POWER GND
R 1
J 1
(-575 6125);
DISPLAY 0.872340 (-575 6125);
PAINT GREEN (-575 6125);
DISPLAY INVISIBLE (-575 6125);
FORCEADD Q_RES..1
(-775 6550);
FORCEPROP 1 LAST PART_NUMBER CS-1002FB04
J 0
(-625 6500);
DISPLAY 0.617021 (-625 6500);
PAINT BLUE (-625 6500);
DISPLAY INVISIBLE (-625 6500);
FORCEPROP 1 LAST VALUE 1
J 2
(-600 6550);
DISPLAY 0.617021 (-600 6550);
PAINT SKYBLUE (-600 6550);
FORCEPROP 1 LAST MATERIAL CHIP
J 0
(-475 6550);
DISPLAY 0.617021 (-475 6550);
PAINT SKYBLUE (-475 6550);
FORCEPROP 1 LAST WATTAGE 1/16W
J 2
(-275 6450);
DISPLAY 0.617021 (-275 6450);
PAINT SKYBLUE (-275 6450);
FORCEPROP 1 LAST TOLERANCE 1%
J 0
(-575 6550);
DISPLAY 0.617021 (-575 6550);
PAINT SKYBLUE (-575 6550);
FORCEPROP 1 LAST PACK_TYPE 0402LF
J 0
(-625 6450);
DISPLAY 0.617021 (-625 6450);
PAINT SKYBLUE (-625 6450);
FORCEPROP 1 LAST LOCATION PR176
J 0
(-1000 6550);
DISPLAY 0.617021 (-1000 6550);
PAINT AQUA (-1000 6550);
FORCEPROP 1 LASTPIN (-875 6550) $PN 1
J 0
(-863 6562);
DISPLAY 0.617021 (-863 6562);
PAINT MONO (-863 6562);
FORCEPROP 1 LASTPIN (-675 6550) $PN 2
J 0
(-713 6562);
DISPLAY 0.617021 (-713 6562);
PAINT MONO (-713 6562);
FORCEPROP 1 LAST PATH I133
J 0
(-825 6700);
DISPLAY 0.978723 (-825 6700);
PAINT WHITE (-825 6700);
DISPLAY INVISIBLE (-825 6700);
FORCEPROP 2 LAST CDS_LIB pure_quanta
J 0
(-775 6550);
DISPLAY INVISIBLE (-775 6550);
FORCEPROP 1 LAST LOCATION PR176
J 0
(-825 6650);
DISPLAY 1.021277 (-825 6650);
PAINT AQUA (-825 6650);
DISPLAY INVISIBLE (-825 6650);
FORCEPROP 0 LAST $SEC 1
J 0
(-825 6650);
DISPLAY 0.680851 (-825 6650);
PAINT MONO (-825 6650);
DISPLAY INVISIBLE (-825 6650);
FORCEPROP 0 LAST CDS_SEC 1
J 0
(-825 6650);
DISPLAY 1.021277 (-825 6650);
DISPLAY INVISIBLE (-825 6650);
FORCEADD VCC15..1
(-300 6675);
FORCEPROP 3 LASTPIN (-300 6625) SIG_NAME P3V3_AUX\g
J 0
(-290 6635);
DISPLAY 0.659574 (-290 6635);
PAINT MONO (-290 6635);
DISPLAY INVISIBLE (-290 6635);
FORCEPROP 1 LAST HDL_POWER P3V3_AUX
J 1
(-300 6725);
DISPLAY 0.617021 (-300 6725);
PAINT GREEN (-300 6725);
FORCEPROP 1 LAST PATH I134
J 0
(-250 6700);
DISPLAY 0.872340 (-250 6700);
PAINT AQUA (-250 6700);
DISPLAY INVISIBLE (-250 6700);
FORCEPROP 2 LAST CDS_LIB logical_power
J 0
(-300 6675);
DISPLAY INVISIBLE (-300 6675);
FORCEADD Q_CAP..1
(-1825 6350);
FORCEPROP 1 LAST PART_NUMBER CH4104K1B00
J 0
(-1775 6275);
DISPLAY 0.638298 (-1775 6275);
DISPLAY INVISIBLE (-1775 6275);
FORCEPROP 1 LAST VALUE 0.1UF
J 0
(-1775 6425);
DISPLAY 0.638298 (-1775 6425);
FORCEPROP 1 LAST VOLTAGE 25V
J 0
(-1775 6375);
DISPLAY 0.638298 (-1775 6375);
FORCEPROP 1 LAST TOLERANCE 10%
J 0
(-1775 6325);
DISPLAY 0.638298 (-1775 6325);
FORCEPROP 1 LAST MATERIAL EMPTY
J 0
(-1775 6300);
DISPLAY 0.638298 (-1775 6300);
PAINT RED (-1775 6300);
FORCEPROP 1 LAST PACK_TYPE 0402
J 0
(-1775 6225);
DISPLAY 0.638298 (-1775 6225);
FORCEPROP 1 LAST LOCATION PC2361
J 0
(-1775 6450);
DISPLAY 0.787234 (-1775 6450);
FORCEPROP 1 LASTPIN (-1825 6450) $PN 1
J 0
(-1815 6430);
DISPLAY 0.787234 (-1815 6430);
PAINT MONO (-1815 6430);
FORCEPROP 1 LASTPIN (-1825 6250) $PN 2
J 0
(-1815 6230);
DISPLAY 0.787234 (-1815 6230);
PAINT MONO (-1815 6230);
FORCEPROP 1 LAST PATH I136
J 0
(-1775 6500);
DISPLAY 0.978723 (-1775 6500);
PAINT WHITE (-1775 6500);
DISPLAY INVISIBLE (-1775 6500);
FORCEPROP 2 LAST CDS_LIB pure_quanta
J 0
(-1825 6350);
DISPLAY INVISIBLE (-1825 6350);
FORCEPROP 0 LAST $SEC 1
J 0
(-1775 6500);
DISPLAY 0.680851 (-1775 6500);
PAINT MONO (-1775 6500);
DISPLAY INVISIBLE (-1775 6500);
FORCEPROP 0 LAST CDS_SEC 1
J 0
(-1775 6500);
DISPLAY 1.021277 (-1775 6500);
DISPLAY INVISIBLE (-1775 6500);
FORCEADD OFFPAGE..5
(-6775 2300);
FORCEPROP 2 LAST $XR0 215 
J 0
(-7030 2300);
DISPLAY 0.638298 (-7030 2300);
PAINT MONO (-7030 2300);
FORCEPROP 2 LAST PATH I14
J 0
(-7025 2350);
DISPLAY 1.021277 (-7025 2350);
DISPLAY INVISIBLE (-7025 2350);
FORCEPROP 2 LAST CDS_LIB standard
J 0
(-6775 2300);
DISPLAY INVISIBLE (-6775 2300);
FORCEPROP 1 LAST OFFPAGE TRUE
J 0
(-6450 2175);
DISPLAY 0.872340 (-6450 2175);
PAINT GREEN (-6450 2175);
DISPLAY INVISIBLE (-6450 2175);
FORCEPROP 1 LAST COMMENT_BODY TRUE
J 0
(-6675 2225);
DISPLAY 0.872340 (-6675 2225);
PAINT GREEN (-6675 2225);
DISPLAY INVISIBLE (-6675 2225);
FORCEADD Q_RES..1
(-6025 2925);
FORCEPROP 1 LAST PART_NUMBER CS11002FB07
J 0
(-5900 2975);
DISPLAY 0.489362 (-5900 2975);
PAINT BLUE (-5900 2975);
DISPLAY INVISIBLE (-5900 2975);
FORCEPROP 1 LAST PACK_TYPE 0402LF
J 0
(-5725 2925);
DISPLAY 0.489362 (-5725 2925);
PAINT SKYBLUE (-5725 2925);
FORCEPROP 1 LAST MATERIAL CHIP
J 0
(-5900 3025);
DISPLAY 0.489362 (-5900 3025);
PAINT SKYBLUE (-5900 3025);
FORCEPROP 1 LAST TOLERANCE 1%
J 0
(-5800 2925);
DISPLAY 0.489362 (-5800 2925);
PAINT SKYBLUE (-5800 2925);
FORCEPROP 1 LAST WATTAGE 1/16W
J 2
(-5650 3025);
DISPLAY 0.489362 (-5650 3025);
PAINT SKYBLUE (-5650 3025);
FORCEPROP 1 LAST VALUE 100
J 2
(-5825 2925);
DISPLAY 0.489362 (-5825 2925);
PAINT SKYBLUE (-5825 2925);
FORCEPROP 1 LAST LOCATION PR586
J 0
(-6225 2925);
DISPLAY 0.617021 (-6225 2925);
PAINT AQUA (-6225 2925);
FORCEPROP 1 LASTPIN (-6125 2925) $PN 1
J 0
(-6113 2937);
DISPLAY 0.617021 (-6113 2937);
FORCEPROP 1 LASTPIN (-5925 2925) $PN 2
J 0
(-5963 2937);
DISPLAY 0.617021 (-5963 2937);
FORCEPROP 1 LAST PATH I15
J 0
(-6075 3075);
DISPLAY 0.978723 (-6075 3075);
PAINT WHITE (-6075 3075);
DISPLAY INVISIBLE (-6075 3075);
FORCEPROP 2 LAST CDS_LIB pure_quanta
J 0
(-6025 2925);
PAINT MONO (-6025 2925);
DISPLAY INVISIBLE (-6025 2925);
FORCEPROP 2 LAST $SEC 1
J 0
(-6075 3125);
DISPLAY 0.680851 (-6075 3125);
PAINT MONO (-6075 3125);
DISPLAY INVISIBLE (-6075 3125);
FORCEPROP 2 LAST CDS_SEC 1
J 0
(-6075 3125);
DISPLAY 1.021277 (-6075 3125);
DISPLAY INVISIBLE (-6075 3125);
FORCEADD VCC15..1
(-6100 2550);
FORCEPROP 3 LASTPIN (-6100 2500) SIG_NAME P3V3_AUX\g
J 0
(-6090 2510);
DISPLAY 0.659574 (-6090 2510);
PAINT MONO (-6090 2510);
DISPLAY INVISIBLE (-6090 2510);
FORCEPROP 1 LAST HDL_POWER P3V3_AUX
J 1
(-6100 2600);
DISPLAY 0.617021 (-6100 2600);
PAINT GREEN (-6100 2600);
FORCEPROP 1 LAST PATH I16
J 0
(-6050 2575);
DISPLAY 0.872340 (-6050 2575);
PAINT AQUA (-6050 2575);
DISPLAY INVISIBLE (-6050 2575);
FORCEPROP 2 LAST CDS_LIB logical_power
J 0
(-6100 2550);
DISPLAY INVISIBLE (-6100 2550);
FORCEADD Q_RES..1
(-5675 2300);
FORCEPROP 1 LAST PART_NUMBER CS00002JB13
J 0
(-5550 2350);
DISPLAY 0.617021 (-5550 2350);
PAINT BLUE (-5550 2350);
DISPLAY INVISIBLE (-5550 2350);
FORCEPROP 1 LAST VALUE 0
J 2
(-5500 2300);
DISPLAY 0.617021 (-5500 2300);
PAINT SKYBLUE (-5500 2300);
FORCEPROP 1 LAST WATTAGE 1/16W
J 2
(-4900 2300);
DISPLAY 0.617021 (-4900 2300);
PAINT SKYBLUE (-4900 2300);
FORCEPROP 1 LAST MATERIAL CHIP
J 0
(-5200 2300);
DISPLAY 0.617021 (-5200 2300);
PAINT SKYBLUE (-5200 2300);
FORCEPROP 1 LAST PACK_TYPE 0402LF
J 0
(-5400 2300);
DISPLAY 0.617021 (-5400 2300);
PAINT SKYBLUE (-5400 2300);
FORCEPROP 1 LAST TOLERANCE 5%
J 0
(-5475 2300);
DISPLAY 0.617021 (-5475 2300);
PAINT SKYBLUE (-5475 2300);
FORCEPROP 1 LAST LOCATION R2376
J 0
(-5925 2300);
DISPLAY 0.617021 (-5925 2300);
PAINT AQUA (-5925 2300);
FORCEPROP 1 LASTPIN (-5775 2300) $PN 1
J 0
(-5763 2312);
DISPLAY 0.617021 (-5763 2312);
FORCEPROP 1 LASTPIN (-5575 2300) $PN 2
J 0
(-5613 2312);
DISPLAY 0.617021 (-5613 2312);
FORCEPROP 1 LAST PATH I17
J 0
(-5725 2450);
DISPLAY 0.978723 (-5725 2450);
PAINT WHITE (-5725 2450);
DISPLAY INVISIBLE (-5725 2450);
FORCEPROP 2 LAST CDS_LIB pure_quanta
J 0
(-5675 2300);
PAINT MONO (-5675 2300);
DISPLAY INVISIBLE (-5675 2300);
FORCEPROP 2 LAST $SEC 1
J 0
(-5725 2500);
DISPLAY 0.680851 (-5725 2500);
PAINT MONO (-5725 2500);
DISPLAY INVISIBLE (-5725 2500);
FORCEPROP 2 LAST CDS_SEC 1
J 0
(-5725 2500);
DISPLAY 1.021277 (-5725 2500);
DISPLAY INVISIBLE (-5725 2500);
FORCEADD OFFPAGE..5
(-5625 2700);
FORCEPROP 2 LAST $XR0 214 
J 0
(-5880 2700);
DISPLAY 0.638298 (-5880 2700);
PAINT MONO (-5880 2700);
FORCEPROP 2 LAST PATH I18
J 0
(-5875 2750);
DISPLAY 1.021277 (-5875 2750);
DISPLAY INVISIBLE (-5875 2750);
FORCEPROP 2 LAST CDS_LIB standard
J 0
(-5625 2700);
DISPLAY INVISIBLE (-5625 2700);
FORCEPROP 1 LAST OFFPAGE TRUE
J 0
(-5300 2575);
DISPLAY 0.872340 (-5300 2575);
PAINT GREEN (-5300 2575);
DISPLAY INVISIBLE (-5300 2575);
FORCEPROP 1 LAST COMMENT_BODY TRUE
J 0
(-5525 2625);
DISPLAY 0.872340 (-5525 2625);
PAINT GREEN (-5525 2625);
DISPLAY INVISIBLE (-5525 2625);
FORCEADD Q_RES..1
(-5250 2450);
FORCEPROP 1 LAST PART_NUMBER CS21002FB06
J 0
(-5125 2500);
DISPLAY 0.510638 (-5125 2500);
PAINT BLUE (-5125 2500);
DISPLAY INVISIBLE (-5125 2500);
FORCEPROP 1 LAST PACK_TYPE 0402LF
J 0
(-4975 2450);
DISPLAY 0.489362 (-4975 2450);
PAINT SKYBLUE (-4975 2450);
FORCEPROP 1 LAST VALUE 1K
J 2
(-5075 2450);
DISPLAY 0.489362 (-5075 2450);
PAINT SKYBLUE (-5075 2450);
FORCEPROP 1 LAST TOLERANCE 1%
J 0
(-5050 2450);
DISPLAY 0.489362 (-5050 2450);
PAINT SKYBLUE (-5050 2450);
FORCEPROP 1 LAST LOCATION R2375
J 0
(-5500 2450);
DISPLAY 0.617021 (-5500 2450);
PAINT AQUA (-5500 2450);
FORCEPROP 1 LASTPIN (-5350 2450) $PN 1
J 0
(-5338 2462);
DISPLAY 0.617021 (-5338 2462);
FORCEPROP 1 LASTPIN (-5150 2450) $PN 2
J 0
(-5188 2462);
DISPLAY 0.617021 (-5188 2462);
FORCEPROP 1 LAST PATH I19
J 0
(-5300 2600);
DISPLAY 0.978723 (-5300 2600);
PAINT WHITE (-5300 2600);
DISPLAY INVISIBLE (-5300 2600);
FORCEPROP 2 LAST CDS_LIB pure_quanta
J 0
(-5250 2450);
PAINT MONO (-5250 2450);
DISPLAY INVISIBLE (-5250 2450);
FORCEPROP 1 LAST WATTAGE 1/16W
J 2
(-4875 2550);
DISPLAY 0.510638 (-4875 2550);
PAINT SKYBLUE (-4875 2550);
DISPLAY INVISIBLE (-4875 2550);
FORCEPROP 1 LAST MATERIAL CHIP
J 0
(-5125 2550);
DISPLAY 0.510638 (-5125 2550);
PAINT SKYBLUE (-5125 2550);
DISPLAY INVISIBLE (-5125 2550);
FORCEPROP 2 LAST $SEC 1
J 0
(-5300 2650);
DISPLAY 0.680851 (-5300 2650);
PAINT MONO (-5300 2650);
DISPLAY INVISIBLE (-5300 2650);
FORCEPROP 2 LAST CDS_SEC 1
J 0
(-5300 2650);
DISPLAY 1.021277 (-5300 2650);
DISPLAY INVISIBLE (-5300 2650);
FORCEADD OFFPAGE..1
(-7000 3075);
FORCEPROP 2 LAST $XR0 16 
J 0
(-7311 3075);
DISPLAY 0.638298 (-7311 3075);
PAINT MONO (-7311 3075);
FORCEPROP 2 LAST PATH I2
J 0
(-7300 3125);
DISPLAY 1.021277 (-7300 3125);
DISPLAY INVISIBLE (-7300 3125);
FORCEPROP 2 LAST CDS_LIB standard
J 0
(-7000 3075);
DISPLAY INVISIBLE (-7000 3075);
FORCEPROP 1 LAST OFFPAGE TRUE
J 0
(-6675 2950);
DISPLAY 0.872340 (-6675 2950);
PAINT GREEN (-6675 2950);
DISPLAY INVISIBLE (-6675 2950);
FORCEPROP 1 LAST COMMENT_BODY TRUE
J 0
(-6875 2975);
DISPLAY 0.872340 (-6875 2975);
PAINT GREEN (-6875 2975);
DISPLAY INVISIBLE (-6875 2975);
FORCEADD Q_RES..1
(-5250 2550);
FORCEPROP 1 LAST PART_NUMBER CS21002FB06
J 0
(-5375 2600);
DISPLAY 0.489362 (-5375 2600);
PAINT BLUE (-5375 2600);
DISPLAY INVISIBLE (-5375 2600);
FORCEPROP 1 LAST WATTAGE 1/16W
J 2
(-5100 2650);
DISPLAY 0.489362 (-5100 2650);
PAINT SKYBLUE (-5100 2650);
FORCEPROP 1 LAST PACK_TYPE 0402LF
J 0
(-4975 2550);
DISPLAY 0.489362 (-4975 2550);
PAINT SKYBLUE (-4975 2550);
FORCEPROP 1 LAST TOLERANCE 1%
J 0
(-5050 2550);
DISPLAY 0.489362 (-5050 2550);
PAINT SKYBLUE (-5050 2550);
FORCEPROP 1 LAST VALUE 1K
J 2
(-5075 2550);
DISPLAY 0.489362 (-5075 2550);
PAINT SKYBLUE (-5075 2550);
FORCEPROP 1 LAST MATERIAL CHIP
J 0
(-5375 2650);
DISPLAY 0.489362 (-5375 2650);
PAINT SKYBLUE (-5375 2650);
FORCEPROP 1 LAST LOCATION R2589
J 0
(-5500 2550);
DISPLAY 0.617021 (-5500 2550);
PAINT AQUA (-5500 2550);
FORCEPROP 1 LASTPIN (-5350 2550) $PN 1
J 0
(-5338 2562);
DISPLAY 0.617021 (-5338 2562);
FORCEPROP 1 LASTPIN (-5150 2550) $PN 2
J 0
(-5188 2562);
DISPLAY 0.617021 (-5188 2562);
FORCEPROP 1 LAST PATH I20
J 0
(-5300 2700);
DISPLAY 0.978723 (-5300 2700);
PAINT WHITE (-5300 2700);
DISPLAY INVISIBLE (-5300 2700);
FORCEPROP 2 LAST CDS_LIB pure_quanta
J 0
(-5250 2550);
PAINT MONO (-5250 2550);
DISPLAY INVISIBLE (-5250 2550);
FORCEPROP 2 LAST $SEC 1
J 0
(-5300 2750);
DISPLAY 0.680851 (-5300 2750);
PAINT MONO (-5300 2750);
DISPLAY INVISIBLE (-5300 2750);
FORCEPROP 2 LAST CDS_SEC 1
J 0
(-5300 2750);
DISPLAY 1.021277 (-5300 2750);
DISPLAY INVISIBLE (-5300 2750);
FORCEADD UNIVERSAL_GND..1
(-5550 2825);
FORCEPROP 3 LASTPIN (-5550 2875) SIG_NAME GND\g
J 0
(-5540 2885);
DISPLAY 0.659574 (-5540 2885);
PAINT MONO (-5540 2885);
DISPLAY INVISIBLE (-5540 2885);
FORCEPROP 1 LAST PATH I21
J 0
(-5475 2825);
DISPLAY 0.872340 (-5475 2825);
PAINT AQUA (-5475 2825);
DISPLAY INVISIBLE (-5475 2825);
FORCEPROP 2 LAST CDS_LIB logical_power
J 0
(-5550 2825);
PAINT MONO (-5550 2825);
DISPLAY INVISIBLE (-5550 2825);
FORCEPROP 1 LAST HDL_POWER GND
J 1
(-5525 2750);
DISPLAY 0.872340 (-5525 2750);
PAINT GREEN (-5525 2750);
DISPLAY INVISIBLE (-5525 2750);
FORCEADD VCC15..1
(-5400 2950);
FORCEPROP 3 LASTPIN (-5400 2900) SIG_NAME P3V3_AUX\g
J 0
(-5390 2910);
DISPLAY 0.659574 (-5390 2910);
PAINT MONO (-5390 2910);
DISPLAY INVISIBLE (-5390 2910);
FORCEPROP 1 LAST HDL_POWER P3V3_AUX
J 1
(-5400 3000);
DISPLAY 0.617021 (-5400 3000);
PAINT GREEN (-5400 3000);
FORCEPROP 1 LAST PATH I22
J 0
(-5350 2975);
DISPLAY 0.872340 (-5350 2975);
PAINT AQUA (-5350 2975);
DISPLAY INVISIBLE (-5350 2975);
FORCEPROP 2 LAST CDS_LIB logical_power
J 0
(-5400 2950);
DISPLAY INVISIBLE (-5400 2950);
FORCEADD Q_RES..1
(-5250 2850);
FORCEPROP 1 LAST PART_NUMBER CS21002FB06
J 0
(-5125 2900);
DISPLAY 0.510638 (-5125 2900);
PAINT BLUE (-5125 2900);
DISPLAY INVISIBLE (-5125 2900);
FORCEPROP 1 LAST VALUE 1K
J 2
(-5100 2850);
DISPLAY 0.489362 (-5100 2850);
PAINT SKYBLUE (-5100 2850);
FORCEPROP 1 LAST PACK_TYPE 0402LF
J 0
(-5000 2850);
DISPLAY 0.489362 (-5000 2850);
PAINT SKYBLUE (-5000 2850);
FORCEPROP 1 LAST TOLERANCE 1%
J 0
(-5075 2850);
DISPLAY 0.489362 (-5075 2850);
PAINT SKYBLUE (-5075 2850);
FORCEPROP 1 LAST LOCATION R2373
J 0
(-5300 2900);
DISPLAY 0.617021 (-5300 2900);
PAINT AQUA (-5300 2900);
FORCEPROP 1 LAST PATH I23
J 0
(-5300 3000);
DISPLAY 0.978723 (-5300 3000);
PAINT WHITE (-5300 3000);
DISPLAY INVISIBLE (-5300 3000);
FORCEPROP 1 LAST MATERIAL CHIP
J 0
(-5125 2950);
DISPLAY 0.510638 (-5125 2950);
PAINT SKYBLUE (-5125 2950);
DISPLAY INVISIBLE (-5125 2950);
FORCEPROP 1 LAST WATTAGE 1/16W
J 2
(-4875 2950);
DISPLAY 0.510638 (-4875 2950);
PAINT SKYBLUE (-4875 2950);
DISPLAY INVISIBLE (-4875 2950);
FORCEPROP 2 LAST CDS_LIB pure_quanta
J 0
(-5250 2850);
DISPLAY INVISIBLE (-5250 2850);
FORCEPROP 0 LAST $SEC 1
J 0
(-4975 2900);
DISPLAY INVISIBLE (-4975 2900);
FORCEPROP 0 LAST CDS_SEC 1
J 0
(-4975 2900);
DISPLAY INVISIBLE (-4975 2900);
FORCEPROP 1 LASTPIN (-5350 2850) $PN 1
J 0
(-5338 2862);
DISPLAY 0.787234 (-5338 2862);
PAINT MONO (-5338 2862);
DISPLAY INVISIBLE (-5338 2862);
FORCEPROP 1 LASTPIN (-5150 2850) $PN 2
J 0
(-5188 2862);
DISPLAY 0.787234 (-5188 2862);
PAINT MONO (-5188 2862);
DISPLAY INVISIBLE (-5188 2862);
FORCEADD Q_SHORT..1
(-5825 3450);
FORCEPROP 1 LAST PART_NUMBER SHORT6
J 0
(-5800 3210);
DISPLAY 0.617021 (-5800 3210);
PAINT BLUE (-5800 3210);
DISPLAY INVISIBLE (-5800 3210);
FORCEPROP 1 LAST MATERIAL EMPTY
J 0
(-5800 3260);
DISPLAY 0.617021 (-5800 3260);
PAINT RED (-5800 3260);
FORCEPROP 2 LAST PACK_TYPE SM
J 0
(-5800 3300);
DISPLAY 0.617021 (-5800 3300);
PAINT SKYBLUE (-5800 3300);
FORCEPROP 1 LAST LOCATION PJ53
J 0
(-5925 3305);
DISPLAY 0.617021 (-5925 3305);
PAINT AQUA (-5925 3305);
FORCEPROP 0 LASTPIN (-5950 3450) $PN 1
J 2
(-5960 3460);
DISPLAY 0.617021 (-5960 3460);
PAINT MONO (-5960 3460);
FORCEPROP 0 LASTPIN (-5700 3450) $PN 2
J 0
(-5690 3460);
DISPLAY 0.617021 (-5690 3460);
PAINT MONO (-5690 3460);
FORCEPROP 1 LAST PATH I24
J 0
(-5900 3655);
DISPLAY 0.723404 (-5900 3655);
PAINT GREEN (-5900 3655);
DISPLAY INVISIBLE (-5900 3655);
FORCEPROP 2 LAST CDS_LIB pure_quanta
J 0
(-5825 3450);
DISPLAY INVISIBLE (-5825 3450);
FORCEPROP 1 LAST NEEDS_NO_SIZE TRUE
J 0
(-5825 3450);
DISPLAY 0.468085 (-5825 3450);
PAINT GREEN (-5825 3450);
DISPLAY INVISIBLE (-5825 3450);
FORCEPROP 1 LAST LOCATION PJ53
J 0
(-5900 3700);
DISPLAY 1.021277 (-5900 3700);
PAINT AQUA (-5900 3700);
DISPLAY INVISIBLE (-5900 3700);
FORCEPROP 0 LAST $SEC 1
J 0
(-5900 3700);
DISPLAY 0.680851 (-5900 3700);
PAINT MONO (-5900 3700);
DISPLAY INVISIBLE (-5900 3700);
FORCEPROP 0 LAST CDS_SEC 1
J 0
(-5900 3700);
DISPLAY 1.021277 (-5900 3700);
DISPLAY INVISIBLE (-5900 3700);
FORCEADD Q_RES..1
(-5750 3600);
FORCEPROP 1 LAST PART_NUMBER CS11002FB07
J 0
(-5625 3650);
DISPLAY 0.489362 (-5625 3650);
PAINT BLUE (-5625 3650);
DISPLAY INVISIBLE (-5625 3650);
FORCEPROP 1 LAST WATTAGE 1/16W
J 2
(-5375 3700);
DISPLAY 0.489362 (-5375 3700);
PAINT SKYBLUE (-5375 3700);
FORCEPROP 1 LAST MATERIAL CHIP
J 0
(-5625 3700);
DISPLAY 0.489362 (-5625 3700);
PAINT SKYBLUE (-5625 3700);
FORCEPROP 1 LAST PACK_TYPE 0402LF
J 0
(-5450 3600);
DISPLAY 0.617021 (-5450 3600);
PAINT SKYBLUE (-5450 3600);
FORCEPROP 1 LAST VALUE 100
J 2
(-5550 3600);
DISPLAY 0.617021 (-5550 3600);
PAINT SKYBLUE (-5550 3600);
FORCEPROP 1 LAST TOLERANCE 1%
J 0
(-5525 3600);
DISPLAY 0.617021 (-5525 3600);
PAINT SKYBLUE (-5525 3600);
FORCEPROP 1 LAST LOCATION PR587
J 0
(-5950 3600);
DISPLAY 0.617021 (-5950 3600);
PAINT AQUA (-5950 3600);
FORCEPROP 1 LASTPIN (-5850 3600) $PN 1
J 0
(-5838 3612);
DISPLAY 0.617021 (-5838 3612);
FORCEPROP 1 LASTPIN (-5650 3600) $PN 2
J 0
(-5688 3612);
DISPLAY 0.617021 (-5688 3612);
FORCEPROP 1 LAST PATH I25
J 0
(-5800 3750);
DISPLAY 0.978723 (-5800 3750);
PAINT WHITE (-5800 3750);
DISPLAY INVISIBLE (-5800 3750);
FORCEPROP 2 LAST CDS_LIB pure_quanta
J 0
(-5750 3600);
PAINT MONO (-5750 3600);
DISPLAY INVISIBLE (-5750 3600);
FORCEPROP 2 LAST $SEC 1
J 0
(-5800 3800);
DISPLAY 0.680851 (-5800 3800);
PAINT MONO (-5800 3800);
DISPLAY INVISIBLE (-5800 3800);
FORCEPROP 2 LAST CDS_SEC 1
J 0
(-5800 3800);
DISPLAY 1.021277 (-5800 3800);
DISPLAY INVISIBLE (-5800 3800);
FORCEADD Q_RES..1
(-5800 4025);
FORCEPROP 1 LAST PART_NUMBER CS11002FB07
J 0
(-5675 4075);
DISPLAY 0.617021 (-5675 4075);
PAINT BLUE (-5675 4075);
DISPLAY INVISIBLE (-5675 4075);
FORCEPROP 1 LAST WATTAGE 1/16W
J 2
(-5375 4125);
DISPLAY 0.617021 (-5375 4125);
PAINT SKYBLUE (-5375 4125);
FORCEPROP 1 LAST VALUE 100
J 2
(-5600 4025);
DISPLAY 0.617021 (-5600 4025);
PAINT SKYBLUE (-5600 4025);
FORCEPROP 1 LAST TOLERANCE 1%
J 0
(-5575 4025);
DISPLAY 0.617021 (-5575 4025);
PAINT SKYBLUE (-5575 4025);
FORCEPROP 1 LAST MATERIAL CHIP
J 0
(-5675 4125);
DISPLAY 0.617021 (-5675 4125);
PAINT SKYBLUE (-5675 4125);
FORCEPROP 1 LAST PACK_TYPE 0402LF
J 0
(-5500 4025);
DISPLAY 0.617021 (-5500 4025);
PAINT SKYBLUE (-5500 4025);
FORCEPROP 1 LAST LOCATION PR527
J 0
(-6000 4025);
DISPLAY 0.617021 (-6000 4025);
PAINT AQUA (-6000 4025);
FORCEPROP 1 LASTPIN (-5900 4025) $PN 1
J 0
(-5888 4037);
DISPLAY 0.617021 (-5888 4037);
FORCEPROP 1 LASTPIN (-5700 4025) $PN 2
J 0
(-5738 4037);
DISPLAY 0.617021 (-5738 4037);
FORCEPROP 1 LAST PATH I26
J 0
(-5850 4175);
DISPLAY 0.978723 (-5850 4175);
PAINT WHITE (-5850 4175);
DISPLAY INVISIBLE (-5850 4175);
FORCEPROP 2 LAST CDS_LIB pure_quanta
J 0
(-5800 4025);
PAINT MONO (-5800 4025);
DISPLAY INVISIBLE (-5800 4025);
FORCEPROP 2 LAST $SEC 1
J 0
(-5850 4225);
DISPLAY 0.680851 (-5850 4225);
PAINT MONO (-5850 4225);
DISPLAY INVISIBLE (-5850 4225);
FORCEPROP 2 LAST CDS_SEC 1
J 0
(-5850 4225);
DISPLAY 1.021277 (-5850 4225);
DISPLAY INVISIBLE (-5850 4225);
FORCEADD VCC15..1
(-5250 3750);
FORCEPROP 3 LASTPIN (-5250 3700) SIG_NAME PVCCFA_EHV_FIVRA_CPU0\g
J 0
(-5240 3710);
DISPLAY 0.659574 (-5240 3710);
PAINT MONO (-5240 3710);
DISPLAY INVISIBLE (-5240 3710);
FORCEPROP 1 LAST HDL_POWER PVCCFA_EHV_FIVRA_CPU0
J 1
(-5250 3800);
DISPLAY 0.617021 (-5250 3800);
PAINT GREEN (-5250 3800);
FORCEPROP 1 LAST PATH I27
J 0
(-5200 3775);
DISPLAY 0.872340 (-5200 3775);
PAINT AQUA (-5200 3775);
DISPLAY INVISIBLE (-5200 3775);
FORCEPROP 2 LAST CDS_LIB logical_power
J 0
(-5250 3750);
DISPLAY INVISIBLE (-5250 3750);
FORCEADD UNIVERSAL_GND..1
(-5275 3925);
FORCEPROP 3 LASTPIN (-5275 3975) SIG_NAME GND\g
J 0
(-5265 3985);
DISPLAY 0.659574 (-5265 3985);
PAINT MONO (-5265 3985);
DISPLAY INVISIBLE (-5265 3985);
FORCEPROP 1 LAST PATH I28
J 0
(-5200 3925);
DISPLAY 0.872340 (-5200 3925);
PAINT AQUA (-5200 3925);
DISPLAY INVISIBLE (-5200 3925);
FORCEPROP 2 LAST CDS_LIB logical_power
J 0
(-5275 3925);
PAINT MONO (-5275 3925);
DISPLAY INVISIBLE (-5275 3925);
FORCEPROP 1 LAST HDL_POWER GND
J 1
(-5250 3850);
DISPLAY 0.872340 (-5250 3850);
PAINT GREEN (-5250 3850);
DISPLAY INVISIBLE (-5250 3850);
FORCEADD OFFPAGE..1
(-7000 4550);
FORCEPROP 2 LAST $XR0 16 
J 0
(-7281 4550);
DISPLAY 0.638298 (-7281 4550);
PAINT MONO (-7281 4550);
FORCEPROP 2 LAST PATH I29
J 0
(-7275 4600);
DISPLAY 1.021277 (-7275 4600);
DISPLAY INVISIBLE (-7275 4600);
FORCEPROP 2 LAST CDS_LIB standard
J 0
(-7000 4550);
DISPLAY INVISIBLE (-7000 4550);
FORCEPROP 1 LAST OFFPAGE TRUE
J 0
(-6675 4425);
DISPLAY 0.872340 (-6675 4425);
PAINT GREEN (-6675 4425);
DISPLAY INVISIBLE (-6675 4425);
FORCEPROP 1 LAST COMMENT_BODY TRUE
J 0
(-6875 4450);
DISPLAY 0.872340 (-6875 4450);
PAINT GREEN (-6875 4450);
DISPLAY INVISIBLE (-6875 4450);
FORCEADD OFFPAGE..1
(-7000 4175);
FORCEPROP 2 LAST $XR0 16 
J 0
(-7281 4175);
DISPLAY 0.638298 (-7281 4175);
PAINT MONO (-7281 4175);
FORCEPROP 2 LAST PATH I3
J 0
(-7275 4225);
DISPLAY 1.021277 (-7275 4225);
DISPLAY INVISIBLE (-7275 4225);
FORCEPROP 2 LAST CDS_LIB standard
J 0
(-7000 4175);
DISPLAY INVISIBLE (-7000 4175);
FORCEPROP 1 LAST OFFPAGE TRUE
J 0
(-6675 4050);
DISPLAY 0.872340 (-6675 4050);
PAINT GREEN (-6675 4050);
DISPLAY INVISIBLE (-6675 4050);
FORCEPROP 1 LAST COMMENT_BODY TRUE
J 0
(-6875 4075);
DISPLAY 0.872340 (-6875 4075);
PAINT GREEN (-6875 4075);
DISPLAY INVISIBLE (-6875 4075);
FORCEADD OFFPAGE..6
(-6650 5250);
FORCEPROP 2 LAST $XR1 284 
J 0
(-7080 5250);
DISPLAY 0.638298 (-7080 5250);
PAINT MONO (-7080 5250);
FORCEPROP 2 LAST $XR0 241 
J 0
(-6960 5250);
DISPLAY 0.638298 (-6960 5250);
PAINT MONO (-6960 5250);
FORCEPROP 2 LAST PATH I30
J 0
(-6950 5300);
DISPLAY 1.021277 (-6950 5300);
DISPLAY INVISIBLE (-6950 5300);
FORCEPROP 2 LAST CDS_LIB standard
J 0
(-6650 5250);
DISPLAY INVISIBLE (-6650 5250);
FORCEPROP 1 LAST OFFPAGE TRUE
J 0
(-6325 5125);
DISPLAY 0.872340 (-6325 5125);
PAINT GREEN (-6325 5125);
DISPLAY INVISIBLE (-6325 5125);
FORCEPROP 1 LAST COMMENT_BODY TRUE
J 0
(-6550 5175);
DISPLAY 0.872340 (-6550 5175);
PAINT GREEN (-6550 5175);
DISPLAY INVISIBLE (-6550 5175);
FORCEADD OFFPAGE..1
(-6650 5400);
FORCEPROP 2 LAST $XR1 284 
J 0
(-7052 5400);
DISPLAY 0.638298 (-7052 5400);
PAINT MONO (-7052 5400);
FORCEPROP 2 LAST $XR0 241 
J 0
(-6932 5400);
DISPLAY 0.638298 (-6932 5400);
PAINT MONO (-6932 5400);
FORCEPROP 2 LAST PATH I31
J 0
(-6925 5450);
DISPLAY 1.021277 (-6925 5450);
DISPLAY INVISIBLE (-6925 5450);
FORCEPROP 2 LAST CDS_LIB standard
J 0
(-6650 5400);
DISPLAY INVISIBLE (-6650 5400);
FORCEPROP 1 LAST OFFPAGE TRUE
J 0
(-6325 5275);
DISPLAY 0.872340 (-6325 5275);
PAINT GREEN (-6325 5275);
DISPLAY INVISIBLE (-6325 5275);
FORCEPROP 1 LAST COMMENT_BODY TRUE
J 0
(-6525 5300);
DISPLAY 0.872340 (-6525 5300);
PAINT GREEN (-6525 5300);
DISPLAY INVISIBLE (-6525 5300);
FORCEADD CONN3_210HP1030BR1..1
R 4
(-6525 5600);
FORCEPROP 1 LAST PART_NUMBER DFHD03MS213
J 0
(-6925 5625);
DISPLAY 0.617021 (-6925 5625);
PAINT BLUE (-6925 5625);
DISPLAY INVISIBLE (-6925 5625);
FORCEPROP 1 LAST LOCATION PJP1
J 0
(-6700 5675);
DISPLAY 0.723404 (-6700 5675);
PAINT GREEN (-6700 5675);
FORCEPROP 2 LASTPIN (-6325 5550) $PN 1
J 0
(-6315 5540);
DISPLAY 0.680851 (-6315 5540);
PAINT MONO (-6315 5540);
FORCEPROP 2 LASTPIN (-6325 5600) $PN 2
J 0
(-6315 5590);
DISPLAY 0.680851 (-6315 5590);
PAINT MONO (-6315 5590);
FORCEPROP 2 LASTPIN (-6325 5650) $PN 3
J 0
(-6315 5640);
DISPLAY 0.680851 (-6315 5640);
PAINT MONO (-6315 5640);
FORCEPROP 1 LAST PATH I32
R 2
J 0
(-6525 5600);
DISPLAY 0.723404 (-6525 5600);
PAINT GREEN (-6525 5600);
DISPLAY INVISIBLE (-6525 5600);
FORCEPROP 2 LAST SEC_TYPE 
R 2
J 2
(-6200 5425);
DISPLAY 1.021277 (-6200 5425);
DISPLAY INVISIBLE (-6200 5425);
FORCEPROP 1 LAST NEEDS_NO_SIZE TRUE
R 2
J 0
(-6525 5600);
DISPLAY 0.723404 (-6525 5600);
PAINT GREEN (-6525 5600);
DISPLAY INVISIBLE (-6525 5600);
FORCEPROP 0 LAST PART_TYPE THLF
R 2
J 0
(-6025 5250);
DISPLAY 0.808511 (-6025 5250);
DISPLAY INVISIBLE (-6025 5250);
FORCEPROP 1 LAST MATERIAL IO
R 2
J 0
(-6500 5475);
DISPLAY 0.723404 (-6500 5475);
PAINT SKYBLUE (-6500 5475);
DISPLAY INVISIBLE (-6500 5475);
FORCEPROP 0 LAST VALUE CONN3_210-HP1-030BR1
R 2
J 0
(-6025 5300);
DISPLAY 0.808511 (-6025 5300);
PAINT SKYBLUE (-6025 5300);
DISPLAY INVISIBLE (-6025 5300);
FORCEPROP 1 LAST CDS_LMAN_SYM_OUTLINE -50,100,50,-100
R 2
J 0
(-6525 5600);
DISPLAY 0.468085 (-6525 5600);
PAINT GREEN (-6525 5600);
DISPLAY INVISIBLE (-6525 5600);
FORCEPROP 2 LAST CDS_LIB pure_quanta
R 2
J 2
(-6525 5600);
DISPLAY INVISIBLE (-6525 5600);
FORCEPROP 2 LAST SEC 1
R 2
J 2
(-6200 5425);
DISPLAY 0.680851 (-6200 5425);
PAINT MONO (-6200 5425);
DISPLAY INVISIBLE (-6200 5425);
FORCEADD OFFPAGE..5
(-6250 5800);
FORCEPROP 2 LAST $XR2 266 
J 0
(-6744 5800);
DISPLAY 0.638298 (-6744 5800);
PAINT MONO (-6744 5800);
FORCEPROP 2 LAST $XR1 274 
J 0
(-6624 5800);
DISPLAY 0.638298 (-6624 5800);
PAINT MONO (-6624 5800);
FORCEPROP 2 LAST $XR0 14 
J 0
(-6504 5800);
DISPLAY 0.638298 (-6504 5800);
PAINT MONO (-6504 5800);
FORCEPROP 2 LAST PATH I33
J 0
(-6500 5850);
DISPLAY 1.021277 (-6500 5850);
DISPLAY INVISIBLE (-6500 5850);
FORCEPROP 2 LAST CDS_LIB standard
J 0
(-6250 5800);
DISPLAY INVISIBLE (-6250 5800);
FORCEPROP 1 LAST OFFPAGE TRUE
J 0
(-5925 5675);
DISPLAY 0.872340 (-5925 5675);
PAINT GREEN (-5925 5675);
DISPLAY INVISIBLE (-5925 5675);
FORCEPROP 1 LAST COMMENT_BODY TRUE
J 0
(-6150 5725);
DISPLAY 0.872340 (-6150 5725);
PAINT GREEN (-6150 5725);
DISPLAY INVISIBLE (-6150 5725);
FORCEADD UNIVERSAL_GND..1
R 1
(-6075 5600);
FORCEPROP 3 LASTPIN (-6125 5600) SIG_NAME GND\g
J 0
(-6115 5610);
DISPLAY 0.659574 (-6115 5610);
PAINT MONO (-6115 5610);
DISPLAY INVISIBLE (-6115 5610);
FORCEPROP 1 LAST PATH I34
R 1
J 0
(-6075 5675);
DISPLAY 0.872340 (-6075 5675);
PAINT AQUA (-6075 5675);
DISPLAY INVISIBLE (-6075 5675);
FORCEPROP 2 LAST CDS_LIB logical_power
J 0
(-6075 5600);
DISPLAY INVISIBLE (-6075 5600);
FORCEPROP 1 LAST HDL_POWER GND
R 1
J 1
(-6000 5625);
DISPLAY 0.872340 (-6000 5625);
PAINT GREEN (-6000 5625);
DISPLAY INVISIBLE (-6000 5625);
FORCEADD OFFPAGE..6
(-6250 5950);
FORCEPROP 2 LAST $XR2 266 
J 0
(-6739 5950);
DISPLAY 0.638298 (-6739 5950);
PAINT MONO (-6739 5950);
FORCEPROP 2 LAST $XR1 274 
J 0
(-6619 5950);
DISPLAY 0.638298 (-6619 5950);
PAINT MONO (-6619 5950);
FORCEPROP 2 LAST $XR0 14 
J 0
(-6499 5950);
DISPLAY 0.638298 (-6499 5950);
PAINT MONO (-6499 5950);
FORCEPROP 2 LAST PATH I35
J 0
(-6475 6000);
DISPLAY 1.021277 (-6475 6000);
DISPLAY INVISIBLE (-6475 6000);
FORCEPROP 2 LAST CDS_LIB standard
J 0
(-6250 5950);
DISPLAY INVISIBLE (-6250 5950);
FORCEPROP 1 LAST OFFPAGE TRUE
J 0
(-5925 5825);
DISPLAY 0.872340 (-5925 5825);
PAINT GREEN (-5925 5825);
DISPLAY INVISIBLE (-5925 5825);
FORCEPROP 1 LAST COMMENT_BODY TRUE
J 0
(-6150 5875);
DISPLAY 0.872340 (-6150 5875);
PAINT GREEN (-6150 5875);
DISPLAY INVISIBLE (-6150 5875);
FORCEADD OFFPAGE..1
(-6250 6100);
FORCEPROP 2 LAST $XR2 274 
J 0
(-6711 6100);
DISPLAY 0.638298 (-6711 6100);
PAINT MONO (-6711 6100);
FORCEPROP 2 LAST $XR1 266 
J 0
(-6591 6100);
DISPLAY 0.638298 (-6591 6100);
PAINT MONO (-6591 6100);
FORCEPROP 2 LAST $XR0 14 
J 0
(-6471 6100);
DISPLAY 0.638298 (-6471 6100);
PAINT MONO (-6471 6100);
FORCEPROP 2 LAST PATH I36
J 0
(-6450 6150);
DISPLAY 1.021277 (-6450 6150);
DISPLAY INVISIBLE (-6450 6150);
FORCEPROP 2 LAST CDS_LIB standard
J 0
(-6250 6100);
DISPLAY INVISIBLE (-6250 6100);
FORCEPROP 1 LAST OFFPAGE TRUE
J 0
(-5925 5975);
DISPLAY 0.872340 (-5925 5975);
PAINT GREEN (-5925 5975);
DISPLAY INVISIBLE (-5925 5975);
FORCEPROP 1 LAST COMMENT_BODY TRUE
J 0
(-6125 6000);
DISPLAY 0.872340 (-6125 6000);
PAINT GREEN (-6125 6000);
DISPLAY INVISIBLE (-6125 6000);
FORCEADD Q_SHORT..1
(-5825 4550);
FORCEPROP 1 LAST PART_NUMBER SHORT6
J 0
(-5800 4310);
DISPLAY 0.617021 (-5800 4310);
PAINT BLUE (-5800 4310);
DISPLAY INVISIBLE (-5800 4310);
FORCEPROP 1 LAST MATERIAL EMPTY
J 0
(-5800 4360);
DISPLAY 0.617021 (-5800 4360);
PAINT RED (-5800 4360);
FORCEPROP 2 LAST PACK_TYPE SM
J 0
(-5800 4400);
DISPLAY 0.617021 (-5800 4400);
PAINT SKYBLUE (-5800 4400);
FORCEPROP 1 LAST LOCATION PJ47
J 0
(-5925 4405);
DISPLAY 0.617021 (-5925 4405);
PAINT AQUA (-5925 4405);
FORCEPROP 0 LASTPIN (-5950 4550) $PN 1
J 2
(-5960 4560);
DISPLAY 0.617021 (-5960 4560);
PAINT MONO (-5960 4560);
FORCEPROP 0 LASTPIN (-5700 4550) $PN 2
J 0
(-5690 4560);
DISPLAY 0.617021 (-5690 4560);
PAINT MONO (-5690 4560);
FORCEPROP 1 LAST PATH I37
J 0
(-5900 4755);
DISPLAY 0.723404 (-5900 4755);
PAINT GREEN (-5900 4755);
DISPLAY INVISIBLE (-5900 4755);
FORCEPROP 1 LAST NEEDS_NO_SIZE TRUE
J 0
(-5825 4550);
DISPLAY 0.468085 (-5825 4550);
PAINT GREEN (-5825 4550);
DISPLAY INVISIBLE (-5825 4550);
FORCEPROP 2 LAST CDS_LIB pure_quanta
J 0
(-5825 4550);
DISPLAY INVISIBLE (-5825 4550);
FORCEPROP 1 LAST LOCATION PJ47
J 0
(-5900 4800);
DISPLAY 1.021277 (-5900 4800);
PAINT AQUA (-5900 4800);
DISPLAY INVISIBLE (-5900 4800);
FORCEPROP 0 LAST $SEC 1
J 0
(-5900 4800);
DISPLAY 0.680851 (-5900 4800);
PAINT MONO (-5900 4800);
DISPLAY INVISIBLE (-5900 4800);
FORCEPROP 0 LAST CDS_SEC 1
J 0
(-5900 4800);
DISPLAY 1.021277 (-5900 4800);
DISPLAY INVISIBLE (-5900 4800);
FORCEADD Q_RES..1
(-5750 4700);
FORCEPROP 1 LAST PART_NUMBER CS11002FB07
J 0
(-5625 4750);
DISPLAY 0.489362 (-5625 4750);
PAINT BLUE (-5625 4750);
DISPLAY INVISIBLE (-5625 4750);
FORCEPROP 1 LAST VALUE 100
J 2
(-5550 4700);
DISPLAY 0.617021 (-5550 4700);
PAINT SKYBLUE (-5550 4700);
FORCEPROP 1 LAST WATTAGE 1/16W
J 2
(-5350 4800);
DISPLAY 0.617021 (-5350 4800);
PAINT SKYBLUE (-5350 4800);
FORCEPROP 1 LAST MATERIAL CHIP
J 0
(-5625 4800);
DISPLAY 0.617021 (-5625 4800);
PAINT SKYBLUE (-5625 4800);
FORCEPROP 1 LAST TOLERANCE 1%
J 0
(-5525 4700);
DISPLAY 0.617021 (-5525 4700);
PAINT SKYBLUE (-5525 4700);
FORCEPROP 1 LAST PACK_TYPE 0402LF
J 0
(-5450 4700);
DISPLAY 0.617021 (-5450 4700);
PAINT SKYBLUE (-5450 4700);
FORCEPROP 1 LAST LOCATION PR531
J 0
(-5950 4700);
DISPLAY 0.617021 (-5950 4700);
PAINT AQUA (-5950 4700);
FORCEPROP 1 LASTPIN (-5850 4700) $PN 1
J 0
(-5838 4712);
DISPLAY 0.617021 (-5838 4712);
FORCEPROP 1 LASTPIN (-5650 4700) $PN 2
J 0
(-5688 4712);
DISPLAY 0.617021 (-5688 4712);
FORCEPROP 1 LAST PATH I38
J 0
(-5800 4850);
DISPLAY 0.978723 (-5800 4850);
PAINT WHITE (-5800 4850);
DISPLAY INVISIBLE (-5800 4850);
FORCEPROP 2 LAST CDS_LIB pure_quanta
J 0
(-5750 4700);
PAINT MONO (-5750 4700);
DISPLAY INVISIBLE (-5750 4700);
FORCEPROP 2 LAST $SEC 1
J 0
(-5800 4900);
DISPLAY 0.680851 (-5800 4900);
PAINT MONO (-5800 4900);
DISPLAY INVISIBLE (-5800 4900);
FORCEPROP 2 LAST CDS_SEC 1
J 0
(-5800 4900);
DISPLAY 1.021277 (-5800 4900);
DISPLAY INVISIBLE (-5800 4900);
FORCEADD VCC15..1
(-5250 4850);
FORCEPROP 3 LASTPIN (-5250 4800) SIG_NAME PVCCIN_CPU0\g
J 0
(-5240 4810);
DISPLAY 0.659574 (-5240 4810);
PAINT MONO (-5240 4810);
DISPLAY INVISIBLE (-5240 4810);
FORCEPROP 1 LAST HDL_POWER PVCCIN_CPU0
J 1
(-5250 4900);
DISPLAY 0.617021 (-5250 4900);
PAINT GREEN (-5250 4900);
FORCEPROP 1 LAST PATH I39
J 0
(-5200 4875);
DISPLAY 0.872340 (-5200 4875);
PAINT AQUA (-5200 4875);
DISPLAY INVISIBLE (-5200 4875);
FORCEPROP 2 LAST CDS_LIB logical_power
J 0
(-5250 4850);
DISPLAY INVISIBLE (-5250 4850);
FORCEADD OFFPAGE..1
(-7000 3450);
FORCEPROP 2 LAST $XR0 16 
J 0
(-7311 3450);
DISPLAY 0.638298 (-7311 3450);
PAINT MONO (-7311 3450);
FORCEPROP 2 LAST PATH I4
J 0
(-7300 3500);
DISPLAY 1.021277 (-7300 3500);
DISPLAY INVISIBLE (-7300 3500);
FORCEPROP 2 LAST CDS_LIB standard
J 0
(-7000 3450);
DISPLAY INVISIBLE (-7000 3450);
FORCEPROP 1 LAST OFFPAGE TRUE
J 0
(-6675 3325);
DISPLAY 0.872340 (-6675 3325);
PAINT GREEN (-6675 3325);
DISPLAY INVISIBLE (-6675 3325);
FORCEPROP 1 LAST COMMENT_BODY TRUE
J 0
(-6875 3350);
DISPLAY 0.872340 (-6875 3350);
PAINT GREEN (-6875 3350);
DISPLAY INVISIBLE (-6875 3350);
FORCEADD Q_RES..1
(-5125 5550);
FORCEPROP 1 LAST PART_NUMBER CS24702JB10
J 0
(-5000 5600);
DISPLAY 0.617021 (-5000 5600);
PAINT BLUE (-5000 5600);
DISPLAY INVISIBLE (-5000 5600);
FORCEPROP 1 LAST MATERIAL EMPTY
J 0
(-4800 5550);
DISPLAY 0.489362 (-4800 5550);
PAINT RED (-4800 5550);
FORCEPROP 1 LAST TOLERANCE 5%
J 0
(-4875 5550);
DISPLAY 0.489362 (-4875 5550);
PAINT SKYBLUE (-4875 5550);
FORCEPROP 1 LAST VALUE 4.7K
J 2
(-4900 5550);
DISPLAY 0.489362 (-4900 5550);
PAINT SKYBLUE (-4900 5550);
FORCEPROP 1 LAST LOCATION R1713
J 0
(-5325 5550);
DISPLAY 0.617021 (-5325 5550);
PAINT AQUA (-5325 5550);
FORCEPROP 1 LASTPIN (-5225 5550) $PN 1
J 0
(-5213 5562);
DISPLAY 0.787234 (-5213 5562);
PAINT MONO (-5213 5562);
FORCEPROP 1 LASTPIN (-5025 5550) $PN 2
J 0
(-5063 5562);
DISPLAY 0.787234 (-5063 5562);
PAINT MONO (-5063 5562);
FORCEPROP 1 LAST PATH I40
J 0
(-5175 5700);
DISPLAY 0.978723 (-5175 5700);
PAINT WHITE (-5175 5700);
DISPLAY INVISIBLE (-5175 5700);
FORCEPROP 2 LAST CDS_LIB pure_quanta
J 0
(-5125 5550);
DISPLAY INVISIBLE (-5125 5550);
FORCEPROP 1 LAST PACK_TYPE 0402LF
J 0
(-4825 5550);
DISPLAY 0.617021 (-4825 5550);
PAINT SKYBLUE (-4825 5550);
DISPLAY INVISIBLE (-4825 5550);
FORCEPROP 1 LAST WATTAGE 1/16W
J 2
(-4750 5650);
DISPLAY 0.617021 (-4750 5650);
PAINT SKYBLUE (-4750 5650);
DISPLAY INVISIBLE (-4750 5650);
FORCEPROP 1 LAST LOCATION R1713
J 0
(-5175 5650);
DISPLAY 1.021277 (-5175 5650);
PAINT AQUA (-5175 5650);
DISPLAY INVISIBLE (-5175 5650);
FORCEPROP 2 LAST $SEC 1
J 0
(-5175 5750);
DISPLAY 0.680851 (-5175 5750);
PAINT MONO (-5175 5750);
DISPLAY INVISIBLE (-5175 5750);
FORCEPROP 2 LAST CDS_SEC 1
J 0
(-5175 5750);
DISPLAY 1.021277 (-5175 5750);
DISPLAY INVISIBLE (-5175 5750);
FORCEADD Q_RES..1
(-5125 5800);
FORCEPROP 1 LAST PART_NUMBER CS00002JB13
J 0
(-5000 5850);
DISPLAY 0.617021 (-5000 5850);
PAINT BLUE (-5000 5850);
DISPLAY INVISIBLE (-5000 5850);
FORCEPROP 1 LAST PACK_TYPE 0402LF
J 0
(-4875 5800);
DISPLAY 0.617021 (-4875 5800);
PAINT SKYBLUE (-4875 5800);
FORCEPROP 1 LAST WATTAGE 1/16W
J 2
(-4700 5900);
DISPLAY 0.617021 (-4700 5900);
PAINT SKYBLUE (-4700 5900);
FORCEPROP 1 LAST MATERIAL CHIP
J 0
(-5000 5900);
DISPLAY 0.617021 (-5000 5900);
PAINT SKYBLUE (-5000 5900);
FORCEPROP 1 LAST TOLERANCE 5%
J 0
(-4950 5800);
DISPLAY 0.617021 (-4950 5800);
PAINT SKYBLUE (-4950 5800);
FORCEPROP 1 LAST VALUE 0
J 2
(-4975 5800);
DISPLAY 0.617021 (-4975 5800);
PAINT SKYBLUE (-4975 5800);
FORCEPROP 1 LAST LOCATION R2370
J 0
(-5325 5800);
DISPLAY 0.617021 (-5325 5800);
PAINT AQUA (-5325 5800);
FORCEPROP 1 LASTPIN (-5225 5800) $PN 1
J 0
(-5213 5812);
DISPLAY 0.617021 (-5213 5812);
PAINT MONO (-5213 5812);
FORCEPROP 1 LASTPIN (-5025 5800) $PN 2
J 0
(-5063 5812);
DISPLAY 0.617021 (-5063 5812);
PAINT MONO (-5063 5812);
FORCEPROP 1 LAST PATH I41
J 0
(-5175 5950);
DISPLAY 0.978723 (-5175 5950);
PAINT WHITE (-5175 5950);
DISPLAY INVISIBLE (-5175 5950);
FORCEPROP 2 LAST CDS_LIB pure_quanta
J 0
(-5125 5800);
DISPLAY INVISIBLE (-5125 5800);
FORCEPROP 1 LAST LOCATION R2370
J 0
(-5175 5900);
DISPLAY 1.021277 (-5175 5900);
PAINT AQUA (-5175 5900);
DISPLAY INVISIBLE (-5175 5900);
FORCEPROP 0 LAST $SEC 1
J 0
(-5175 5900);
DISPLAY 0.680851 (-5175 5900);
PAINT MONO (-5175 5900);
DISPLAY INVISIBLE (-5175 5900);
FORCEPROP 0 LAST CDS_SEC 1
J 0
(-5175 5900);
DISPLAY 1.021277 (-5175 5900);
DISPLAY INVISIBLE (-5175 5900);
FORCEADD Q_RES..1
(-5125 5600);
FORCEPROP 1 LAST PART_NUMBER CS24702JB10
J 0
(-5000 5650);
DISPLAY 0.489362 (-5000 5650);
PAINT BLUE (-5000 5650);
DISPLAY INVISIBLE (-5000 5650);
FORCEPROP 1 LAST WATTAGE 1/16W
J 2
(-4650 5700);
DISPLAY 0.489362 (-4650 5700);
PAINT SKYBLUE (-4650 5700);
FORCEPROP 1 LAST PACK_TYPE 0402LF
J 0
(-5000 5700);
DISPLAY 0.489362 (-5000 5700);
PAINT SKYBLUE (-5000 5700);
FORCEPROP 1 LAST MATERIAL EMPTY
J 0
(-4800 5600);
DISPLAY 0.489362 (-4800 5600);
PAINT RED (-4800 5600);
FORCEPROP 1 LAST TOLERANCE 5%
J 0
(-4875 5600);
DISPLAY 0.489362 (-4875 5600);
PAINT SKYBLUE (-4875 5600);
FORCEPROP 1 LAST VALUE 4.7K
J 2
(-4900 5600);
DISPLAY 0.489362 (-4900 5600);
PAINT SKYBLUE (-4900 5600);
FORCEPROP 1 LAST LOCATION R1712
J 0
(-5325 5600);
DISPLAY 0.617021 (-5325 5600);
PAINT AQUA (-5325 5600);
FORCEPROP 1 LASTPIN (-5225 5600) $PN 1
J 0
(-5213 5612);
DISPLAY 0.787234 (-5213 5612);
PAINT MONO (-5213 5612);
FORCEPROP 1 LASTPIN (-5025 5600) $PN 2
J 0
(-5063 5612);
DISPLAY 0.787234 (-5063 5612);
PAINT MONO (-5063 5612);
FORCEPROP 1 LAST PATH I42
J 0
(-5175 5750);
DISPLAY 0.978723 (-5175 5750);
PAINT WHITE (-5175 5750);
DISPLAY INVISIBLE (-5175 5750);
FORCEPROP 2 LAST CDS_LIB pure_quanta
J 0
(-5125 5600);
DISPLAY INVISIBLE (-5125 5600);
FORCEPROP 1 LAST LOCATION R1712
J 0
(-5175 5700);
DISPLAY 1.021277 (-5175 5700);
PAINT AQUA (-5175 5700);
DISPLAY INVISIBLE (-5175 5700);
FORCEPROP 2 LAST $SEC 1
J 0
(-5175 5800);
DISPLAY 0.680851 (-5175 5800);
PAINT MONO (-5175 5800);
DISPLAY INVISIBLE (-5175 5800);
FORCEPROP 2 LAST CDS_SEC 1
J 0
(-5175 5800);
DISPLAY 1.021277 (-5175 5800);
DISPLAY INVISIBLE (-5175 5800);
FORCEADD Q_RES..1
(-5125 5950);
FORCEPROP 1 LAST PART_NUMBER CS00002JB13
J 0
(-5000 6000);
DISPLAY 0.617021 (-5000 6000);
PAINT BLUE (-5000 6000);
DISPLAY INVISIBLE (-5000 6000);
FORCEPROP 1 LAST VALUE 0
J 2
(-4975 5950);
DISPLAY 0.617021 (-4975 5950);
PAINT SKYBLUE (-4975 5950);
FORCEPROP 1 LAST TOLERANCE 5%
J 0
(-4950 5950);
DISPLAY 0.617021 (-4950 5950);
PAINT SKYBLUE (-4950 5950);
FORCEPROP 1 LAST PACK_TYPE 0402LF
J 0
(-4875 5950);
DISPLAY 0.617021 (-4875 5950);
PAINT SKYBLUE (-4875 5950);
FORCEPROP 1 LAST WATTAGE 1/16W
J 2
(-4700 6050);
DISPLAY 0.617021 (-4700 6050);
PAINT SKYBLUE (-4700 6050);
FORCEPROP 1 LAST MATERIAL CHIP
J 0
(-5000 6050);
DISPLAY 0.617021 (-5000 6050);
PAINT SKYBLUE (-5000 6050);
FORCEPROP 1 LAST LOCATION R2369
J 0
(-5325 5950);
DISPLAY 0.617021 (-5325 5950);
PAINT AQUA (-5325 5950);
FORCEPROP 1 LASTPIN (-5225 5950) $PN 1
J 0
(-5213 5962);
DISPLAY 0.617021 (-5213 5962);
PAINT MONO (-5213 5962);
FORCEPROP 1 LASTPIN (-5025 5950) $PN 2
J 0
(-5063 5962);
DISPLAY 0.617021 (-5063 5962);
PAINT MONO (-5063 5962);
FORCEPROP 1 LAST PATH I43
J 0
(-5175 6100);
DISPLAY 0.978723 (-5175 6100);
PAINT WHITE (-5175 6100);
DISPLAY INVISIBLE (-5175 6100);
FORCEPROP 2 LAST CDS_LIB pure_quanta
J 0
(-5125 5950);
DISPLAY INVISIBLE (-5125 5950);
FORCEPROP 1 LAST LOCATION R2369
J 0
(-5175 6050);
DISPLAY 1.021277 (-5175 6050);
PAINT AQUA (-5175 6050);
DISPLAY INVISIBLE (-5175 6050);
FORCEPROP 0 LAST $SEC 1
J 0
(-5175 6050);
DISPLAY 0.680851 (-5175 6050);
PAINT MONO (-5175 6050);
DISPLAY INVISIBLE (-5175 6050);
FORCEPROP 0 LAST CDS_SEC 1
J 0
(-5175 6050);
DISPLAY 1.021277 (-5175 6050);
DISPLAY INVISIBLE (-5175 6050);
FORCEADD Q_RES..1
(-5125 6100);
FORCEPROP 1 LAST PART_NUMBER CS11502FB07
J 0
(-5000 6150);
DISPLAY 0.617021 (-5000 6150);
PAINT BLUE (-5000 6150);
DISPLAY INVISIBLE (-5000 6150);
FORCEPROP 1 LAST WATTAGE 1/16W
J 2
(-4700 6200);
DISPLAY 0.617021 (-4700 6200);
PAINT SKYBLUE (-4700 6200);
FORCEPROP 1 LAST PACK_TYPE 0402LF
J 0
(-4775 6100);
DISPLAY 0.617021 (-4775 6100);
PAINT SKYBLUE (-4775 6100);
FORCEPROP 1 LAST TOLERANCE 1%
J 0
(-4875 6100);
DISPLAY 0.617021 (-4875 6100);
PAINT SKYBLUE (-4875 6100);
FORCEPROP 1 LAST VALUE 150
J 2
(-4900 6100);
DISPLAY 0.617021 (-4900 6100);
PAINT SKYBLUE (-4900 6100);
FORCEPROP 1 LAST MATERIAL CHIP
J 0
(-5000 6200);
DISPLAY 0.617021 (-5000 6200);
PAINT SKYBLUE (-5000 6200);
FORCEPROP 1 LAST LOCATION R2368
J 0
(-5325 6100);
DISPLAY 0.617021 (-5325 6100);
PAINT AQUA (-5325 6100);
FORCEPROP 1 LASTPIN (-5225 6100) $PN 1
J 0
(-5213 6112);
DISPLAY 0.617021 (-5213 6112);
PAINT MONO (-5213 6112);
FORCEPROP 1 LASTPIN (-5025 6100) $PN 2
J 0
(-5063 6112);
DISPLAY 0.617021 (-5063 6112);
PAINT MONO (-5063 6112);
FORCEPROP 1 LAST PATH I44
J 0
(-5175 6250);
DISPLAY 0.978723 (-5175 6250);
PAINT WHITE (-5175 6250);
DISPLAY INVISIBLE (-5175 6250);
FORCEPROP 2 LAST CDS_LIB pure_quanta
J 0
(-5125 6100);
DISPLAY INVISIBLE (-5125 6100);
FORCEPROP 1 LAST LOCATION R2368
J 0
(-4975 6175);
DISPLAY 1.021277 (-4975 6175);
PAINT AQUA (-4975 6175);
DISPLAY INVISIBLE (-4975 6175);
FORCEPROP 0 LAST $SEC 1
J 0
(-4975 6175);
DISPLAY 0.680851 (-4975 6175);
PAINT MONO (-4975 6175);
DISPLAY INVISIBLE (-4975 6175);
FORCEPROP 0 LAST CDS_SEC 1
J 0
(-4975 6175);
DISPLAY 1.021277 (-4975 6175);
DISPLAY INVISIBLE (-4975 6175);
FORCEADD OFFPAGE..5
(-6250 6550);
FORCEPROP 2 LAST $XR1 253 
J 0
(-6655 6550);
DISPLAY 0.638298 (-6655 6550);
PAINT MONO (-6655 6550);
FORCEPROP 2 LAST $XR0 213 
J 0
(-6535 6550);
DISPLAY 0.638298 (-6535 6550);
PAINT MONO (-6535 6550);
FORCEPROP 2 LAST PATH I45
J 0
(-6525 6600);
DISPLAY 1.021277 (-6525 6600);
DISPLAY INVISIBLE (-6525 6600);
FORCEPROP 2 LAST CDS_LIB standard
J 0
(-6250 6550);
DISPLAY INVISIBLE (-6250 6550);
FORCEPROP 1 LAST OFFPAGE TRUE
J 0
(-5925 6425);
DISPLAY 0.872340 (-5925 6425);
PAINT GREEN (-5925 6425);
DISPLAY INVISIBLE (-5925 6425);
FORCEPROP 1 LAST COMMENT_BODY TRUE
J 0
(-6150 6475);
DISPLAY 0.872340 (-6150 6475);
PAINT GREEN (-6150 6475);
DISPLAY INVISIBLE (-6150 6475);
FORCEADD OFFPAGE..1
(-6250 6400);
FORCEPROP 2 LAST $XR0 222 
J 0
(-6502 6400);
DISPLAY 0.638298 (-6502 6400);
PAINT MONO (-6502 6400);
FORCEPROP 2 LAST PATH I46
J 0
(-6500 6450);
DISPLAY 1.021277 (-6500 6450);
DISPLAY INVISIBLE (-6500 6450);
FORCEPROP 2 LAST CDS_LIB standard
J 0
(-6250 6400);
DISPLAY INVISIBLE (-6250 6400);
FORCEPROP 1 LAST OFFPAGE TRUE
J 0
(-5925 6275);
DISPLAY 0.872340 (-5925 6275);
PAINT GREEN (-5925 6275);
DISPLAY INVISIBLE (-5925 6275);
FORCEPROP 1 LAST COMMENT_BODY TRUE
J 0
(-6125 6300);
DISPLAY 0.872340 (-6125 6300);
PAINT GREEN (-6125 6300);
DISPLAY INVISIBLE (-6125 6300);
FORCEADD VCC15..1
(-5550 6800);
FORCEPROP 3 LASTPIN (-5550 6750) SIG_NAME P3V3_AUX\g
J 0
(-5540 6760);
DISPLAY 0.659574 (-5540 6760);
PAINT MONO (-5540 6760);
DISPLAY INVISIBLE (-5540 6760);
FORCEPROP 1 LAST HDL_POWER P3V3_AUX
J 1
(-5550 6850);
DISPLAY 0.617021 (-5550 6850);
PAINT GREEN (-5550 6850);
FORCEPROP 1 LAST PATH I47
J 0
(-5500 6825);
DISPLAY 0.872340 (-5500 6825);
PAINT AQUA (-5500 6825);
DISPLAY INVISIBLE (-5500 6825);
FORCEPROP 2 LAST CDS_LIB logical_power
J 0
(-5550 6800);
PAINT MONO (-5550 6800);
DISPLAY INVISIBLE (-5550 6800);
FORCEADD Q_RES..1
(-5125 6400);
FORCEPROP 1 LAST PART_NUMBER CS00002JB13
J 0
(-5000 6450);
DISPLAY 0.617021 (-5000 6450);
PAINT BLUE (-5000 6450);
DISPLAY INVISIBLE (-5000 6450);
FORCEPROP 1 LAST VALUE 0
J 2
(-4975 6400);
DISPLAY 0.617021 (-4975 6400);
PAINT SKYBLUE (-4975 6400);
FORCEPROP 1 LAST WATTAGE 1/16W
J 2
(-4700 6500);
DISPLAY 0.617021 (-4700 6500);
PAINT SKYBLUE (-4700 6500);
FORCEPROP 1 LAST TOLERANCE 5%
J 0
(-4950 6400);
DISPLAY 0.617021 (-4950 6400);
PAINT SKYBLUE (-4950 6400);
FORCEPROP 1 LAST PACK_TYPE 0402LF
J 0
(-4875 6400);
DISPLAY 0.617021 (-4875 6400);
PAINT SKYBLUE (-4875 6400);
FORCEPROP 1 LAST MATERIAL CHIP
J 0
(-5000 6500);
DISPLAY 0.617021 (-5000 6500);
PAINT SKYBLUE (-5000 6500);
FORCEPROP 1 LAST LOCATION R2591
J 0
(-5325 6400);
DISPLAY 0.617021 (-5325 6400);
PAINT AQUA (-5325 6400);
FORCEPROP 1 LASTPIN (-5225 6400) $PN 1
J 0
(-5213 6412);
DISPLAY 0.617021 (-5213 6412);
PAINT MONO (-5213 6412);
FORCEPROP 1 LASTPIN (-5025 6400) $PN 2
J 0
(-5063 6412);
DISPLAY 0.617021 (-5063 6412);
PAINT MONO (-5063 6412);
FORCEPROP 1 LAST PATH I48
J 0
(-5175 6550);
DISPLAY 0.978723 (-5175 6550);
PAINT WHITE (-5175 6550);
DISPLAY INVISIBLE (-5175 6550);
FORCEPROP 2 LAST CDS_LIB pure_quanta
J 0
(-5125 6400);
DISPLAY INVISIBLE (-5125 6400);
FORCEPROP 1 LAST LOCATION R2591
J 0
(-5175 6500);
DISPLAY 1.021277 (-5175 6500);
PAINT AQUA (-5175 6500);
DISPLAY INVISIBLE (-5175 6500);
FORCEPROP 0 LAST $SEC 1
J 0
(-5175 6500);
DISPLAY 0.680851 (-5175 6500);
PAINT MONO (-5175 6500);
DISPLAY INVISIBLE (-5175 6500);
FORCEPROP 0 LAST CDS_SEC 1
J 0
(-5175 6500);
DISPLAY 1.021277 (-5175 6500);
DISPLAY INVISIBLE (-5175 6500);
FORCEADD Q_RES..1
(-5125 6550);
FORCEPROP 1 LAST PART_NUMBER CS00002JB13
J 0
(-5000 6600);
DISPLAY 0.617021 (-5000 6600);
PAINT BLUE (-5000 6600);
DISPLAY INVISIBLE (-5000 6600);
FORCEPROP 1 LAST VALUE 0
J 2
(-4975 6550);
DISPLAY 0.617021 (-4975 6550);
PAINT SKYBLUE (-4975 6550);
FORCEPROP 1 LAST TOLERANCE 5%
J 0
(-4950 6550);
DISPLAY 0.617021 (-4950 6550);
PAINT SKYBLUE (-4950 6550);
FORCEPROP 1 LAST MATERIAL CHIP
J 0
(-5000 6650);
DISPLAY 0.617021 (-5000 6650);
PAINT SKYBLUE (-5000 6650);
FORCEPROP 1 LAST WATTAGE 1/16W
J 2
(-4700 6650);
DISPLAY 0.617021 (-4700 6650);
PAINT SKYBLUE (-4700 6650);
FORCEPROP 1 LAST PACK_TYPE 0402LF
J 0
(-4875 6550);
DISPLAY 0.617021 (-4875 6550);
PAINT SKYBLUE (-4875 6550);
FORCEPROP 1 LAST LOCATION R2366
J 0
(-5325 6550);
DISPLAY 0.617021 (-5325 6550);
PAINT AQUA (-5325 6550);
FORCEPROP 1 LASTPIN (-5225 6550) $PN 1
J 0
(-5213 6562);
DISPLAY 0.617021 (-5213 6562);
PAINT MONO (-5213 6562);
FORCEPROP 1 LASTPIN (-5025 6550) $PN 2
J 0
(-5063 6562);
DISPLAY 0.617021 (-5063 6562);
PAINT MONO (-5063 6562);
FORCEPROP 1 LAST PATH I49
J 0
(-5175 6700);
DISPLAY 0.978723 (-5175 6700);
PAINT WHITE (-5175 6700);
DISPLAY INVISIBLE (-5175 6700);
FORCEPROP 2 LAST CDS_LIB pure_quanta
J 0
(-5125 6550);
DISPLAY INVISIBLE (-5125 6550);
FORCEPROP 1 LAST LOCATION R2366
J 0
(-5175 6650);
DISPLAY 1.021277 (-5175 6650);
PAINT AQUA (-5175 6650);
DISPLAY INVISIBLE (-5175 6650);
FORCEPROP 0 LAST $SEC 1
J 0
(-5175 6650);
DISPLAY 0.680851 (-5175 6650);
PAINT MONO (-5175 6650);
DISPLAY INVISIBLE (-5175 6650);
FORCEPROP 0 LAST CDS_SEC 1
J 0
(-5175 6650);
DISPLAY 1.021277 (-5175 6650);
DISPLAY INVISIBLE (-5175 6650);
FORCEADD Q_RES..1
(-6050 1450);
FORCEPROP 1 LAST PART_NUMBER CS32802FB05
J 0
(-6150 1525);
DISPLAY 0.617021 (-6150 1525);
PAINT BLUE (-6150 1525);
DISPLAY INVISIBLE (-6150 1525);
FORCEPROP 1 LAST VALUE 28K
J 2
(-5825 1450);
DISPLAY 0.617021 (-5825 1450);
PAINT SKYBLUE (-5825 1450);
FORCEPROP 1 LAST TOLERANCE 1%
J 0
(-5800 1450);
DISPLAY 0.617021 (-5800 1450);
PAINT SKYBLUE (-5800 1450);
FORCEPROP 1 LAST PACK_TYPE 0402LF
J 0
(-5725 1450);
DISPLAY 0.617021 (-5725 1450);
PAINT SKYBLUE (-5725 1450);
FORCEPROP 1 LAST WATTAGE 1/16W
J 2
(-5825 1575);
DISPLAY 0.617021 (-5825 1575);
PAINT SKYBLUE (-5825 1575);
FORCEPROP 1 LAST MATERIAL EMPTY
J 0
(-6150 1575);
DISPLAY 0.617021 (-6150 1575);
PAINT RED (-6150 1575);
FORCEPROP 1 LAST LOCATION PR159
J 0
(-6275 1450);
DISPLAY 0.617021 (-6275 1450);
PAINT AQUA (-6275 1450);
FORCEPROP 1 LASTPIN (-6150 1450) $PN 1
J 0
(-6138 1462);
DISPLAY 0.617021 (-6138 1462);
PAINT MONO (-6138 1462);
FORCEPROP 1 LASTPIN (-5950 1450) $PN 2
J 0
(-5988 1462);
DISPLAY 0.617021 (-5988 1462);
PAINT MONO (-5988 1462);
FORCEPROP 1 LAST PATH I5
J 0
(-6100 1600);
DISPLAY 0.978723 (-6100 1600);
PAINT WHITE (-6100 1600);
DISPLAY INVISIBLE (-6100 1600);
FORCEPROP 2 LAST CDS_LIB pure_quanta
J 0
(-6050 1450);
DISPLAY INVISIBLE (-6050 1450);
FORCEPROP 1 LAST LOCATION PR159
J 0
(-6125 1575);
DISPLAY 1.021277 (-6125 1575);
PAINT AQUA (-6125 1575);
DISPLAY INVISIBLE (-6125 1575);
FORCEPROP 0 LAST $SEC 1
J 0
(-6125 1575);
DISPLAY 0.680851 (-6125 1575);
PAINT MONO (-6125 1575);
DISPLAY INVISIBLE (-6125 1575);
FORCEPROP 0 LAST CDS_SEC 1
J 0
(-6125 1575);
DISPLAY 1.021277 (-6125 1575);
DISPLAY INVISIBLE (-6125 1575);
FORCEADD Q_RES..1
(-5125 6700);
FORCEPROP 1 LAST PART_NUMBER CS21002FB06
J 0
(-5000 6750);
DISPLAY 0.617021 (-5000 6750);
PAINT BLUE (-5000 6750);
DISPLAY INVISIBLE (-5000 6750);
FORCEPROP 1 LAST TOLERANCE 1%
J 0
(-4925 6700);
DISPLAY 0.617021 (-4925 6700);
PAINT SKYBLUE (-4925 6700);
FORCEPROP 1 LAST VALUE 1K
J 2
(-4950 6700);
DISPLAY 0.617021 (-4950 6700);
PAINT SKYBLUE (-4950 6700);
FORCEPROP 1 LAST WATTAGE 1/16W
J 2
(-4700 6800);
DISPLAY 0.617021 (-4700 6800);
PAINT SKYBLUE (-4700 6800);
FORCEPROP 1 LAST MATERIAL CHIP
J 0
(-5000 6800);
DISPLAY 0.617021 (-5000 6800);
PAINT SKYBLUE (-5000 6800);
FORCEPROP 1 LAST PACK_TYPE 0402LF
J 0
(-4825 6700);
DISPLAY 0.617021 (-4825 6700);
PAINT SKYBLUE (-4825 6700);
FORCEPROP 1 LAST LOCATION R2365
J 0
(-5325 6700);
DISPLAY 0.617021 (-5325 6700);
PAINT AQUA (-5325 6700);
FORCEPROP 1 LASTPIN (-5225 6700) $PN 1
J 0
(-5213 6712);
DISPLAY 0.617021 (-5213 6712);
PAINT MONO (-5213 6712);
FORCEPROP 1 LASTPIN (-5025 6700) $PN 2
J 0
(-5063 6712);
DISPLAY 0.617021 (-5063 6712);
PAINT MONO (-5063 6712);
FORCEPROP 1 LAST PATH I50
J 0
(-5175 6850);
DISPLAY 0.978723 (-5175 6850);
PAINT WHITE (-5175 6850);
DISPLAY INVISIBLE (-5175 6850);
FORCEPROP 2 LAST CDS_LIB pure_quanta
J 0
(-5125 6700);
DISPLAY INVISIBLE (-5125 6700);
FORCEPROP 1 LAST LOCATION R2365
J 0
(-5175 6800);
DISPLAY 1.021277 (-5175 6800);
PAINT AQUA (-5175 6800);
DISPLAY INVISIBLE (-5175 6800);
FORCEPROP 0 LAST $SEC 1
J 0
(-5175 6800);
DISPLAY 0.680851 (-5175 6800);
PAINT MONO (-5175 6800);
DISPLAY INVISIBLE (-5175 6800);
FORCEPROP 0 LAST CDS_SEC 1
J 0
(-5175 6800);
DISPLAY 1.021277 (-5175 6800);
DISPLAY INVISIBLE (-5175 6800);
FORCEADD Q_RES..2
(-4750 900);
FORCEPROP 1 LAST PART_NUMBER CS00002JB13
J 0
(-4710 775);
DISPLAY 0.617021 (-4710 775);
PAINT BLUE (-4710 775);
DISPLAY INVISIBLE (-4710 775);
FORCEPROP 1 LAST TOLERANCE 5%
J 0
(-4705 925);
DISPLAY 0.617021 (-4705 925);
PAINT SKYBLUE (-4705 925);
FORCEPROP 1 LAST WATTAGE 1/16W
J 0
(-4710 875);
DISPLAY 0.617021 (-4710 875);
PAINT SKYBLUE (-4710 875);
FORCEPROP 1 LAST MATERIAL CHIP
J 0
(-4710 825);
DISPLAY 0.617021 (-4710 825);
PAINT SKYBLUE (-4710 825);
FORCEPROP 1 LAST VALUE 0
J 0
(-4705 975);
DISPLAY 0.617021 (-4705 975);
PAINT SKYBLUE (-4705 975);
FORCEPROP 1 LAST PACK_TYPE 0402LF
J 0
(-4710 725);
DISPLAY 0.617021 (-4710 725);
PAINT SKYBLUE (-4710 725);
FORCEPROP 1 LAST LOCATION PR158
J 0
(-4705 1025);
DISPLAY 0.617021 (-4705 1025);
PAINT AQUA (-4705 1025);
FORCEPROP 1 LASTPIN (-4750 1000) $PN 1
J 0
(-4745 962);
DISPLAY 0.617021 (-4745 962);
PAINT MONO (-4745 962);
FORCEPROP 1 LASTPIN (-4750 800) $PN 2
J 0
(-4745 810);
DISPLAY 0.617021 (-4745 810);
PAINT MONO (-4745 810);
FORCEPROP 1 LAST PATH I51
J 0
(-4700 1075);
DISPLAY 0.978723 (-4700 1075);
PAINT WHITE (-4700 1075);
DISPLAY INVISIBLE (-4700 1075);
FORCEPROP 2 LAST CDS_LIB pure_quanta
J 0
(-4750 900);
DISPLAY INVISIBLE (-4750 900);
FORCEPROP 1 LAST LOCATION PR158
J 0
(-4700 1075);
DISPLAY 1.021277 (-4700 1075);
PAINT AQUA (-4700 1075);
DISPLAY INVISIBLE (-4700 1075);
FORCEPROP 0 LAST $SEC 1
J 0
(-4700 1075);
DISPLAY 0.680851 (-4700 1075);
PAINT MONO (-4700 1075);
DISPLAY INVISIBLE (-4700 1075);
FORCEPROP 0 LAST CDS_SEC 1
J 0
(-4700 1075);
DISPLAY 1.021277 (-4700 1075);
DISPLAY INVISIBLE (-4700 1075);
FORCEADD UNIVERSAL_GND..1
(-4425 600);
FORCEPROP 3 LASTPIN (-4425 650) SIG_NAME GND\g
J 0
(-4415 660);
DISPLAY 0.659574 (-4415 660);
PAINT MONO (-4415 660);
DISPLAY INVISIBLE (-4415 660);
FORCEPROP 1 LAST PATH I52
J 0
(-4350 600);
DISPLAY 0.872340 (-4350 600);
PAINT AQUA (-4350 600);
DISPLAY INVISIBLE (-4350 600);
FORCEPROP 2 LAST CDS_LIB logical_power
J 0
(-4425 600);
PAINT MONO (-4425 600);
DISPLAY INVISIBLE (-4425 600);
FORCEPROP 1 LAST HDL_POWER GND
J 1
(-4400 525);
DISPLAY 0.872340 (-4400 525);
PAINT GREEN (-4400 525);
DISPLAY INVISIBLE (-4400 525);
FORCEADD Q_CAP..1
(-4425 900);
FORCEPROP 1 LAST PART_NUMBER CH4104K1B00
J 0
(-4375 725);
DISPLAY 0.617021 (-4375 725);
PAINT BLUE (-4375 725);
DISPLAY INVISIBLE (-4375 725);
FORCEPROP 1 LAST TOLERANCE 10%
J 0
(-4375 875);
DISPLAY 0.617021 (-4375 875);
PAINT SKYBLUE (-4375 875);
FORCEPROP 1 LAST PACK_TYPE 0402
J 0
(-4375 775);
DISPLAY 0.617021 (-4375 775);
PAINT SKYBLUE (-4375 775);
FORCEPROP 1 LAST VOLTAGE 25V
J 0
(-4375 925);
DISPLAY 0.617021 (-4375 925);
PAINT SKYBLUE (-4375 925);
FORCEPROP 1 LAST VALUE 0.1UF
J 0
(-4375 975);
DISPLAY 0.617021 (-4375 975);
PAINT SKYBLUE (-4375 975);
FORCEPROP 1 LAST MATERIAL EMPTY
J 0
(-4375 825);
DISPLAY 0.617021 (-4375 825);
PAINT RED (-4375 825);
FORCEPROP 1 LAST LOCATION PC329
J 0
(-4375 1025);
DISPLAY 0.617021 (-4375 1025);
PAINT AQUA (-4375 1025);
FORCEPROP 1 LASTPIN (-4425 1000) $PN 1
J 0
(-4415 980);
DISPLAY 0.617021 (-4415 980);
PAINT MONO (-4415 980);
FORCEPROP 1 LASTPIN (-4425 800) $PN 2
J 0
(-4415 780);
DISPLAY 0.617021 (-4415 780);
PAINT MONO (-4415 780);
FORCEPROP 1 LAST PATH I53
J 0
(-4375 1050);
DISPLAY 0.978723 (-4375 1050);
PAINT WHITE (-4375 1050);
DISPLAY INVISIBLE (-4375 1050);
FORCEPROP 2 LAST CDS_LIB pure_quanta
J 0
(-4425 900);
DISPLAY INVISIBLE (-4425 900);
FORCEPROP 1 LAST LOCATION PC329
J 0
(-4375 1075);
DISPLAY 1.021277 (-4375 1075);
PAINT AQUA (-4375 1075);
DISPLAY INVISIBLE (-4375 1075);
FORCEPROP 0 LAST $SEC 1
J 0
(-4375 1075);
DISPLAY 0.680851 (-4375 1075);
PAINT MONO (-4375 1075);
DISPLAY INVISIBLE (-4375 1075);
FORCEPROP 0 LAST CDS_SEC 1
J 0
(-4375 1075);
DISPLAY 1.021277 (-4375 1075);
DISPLAY INVISIBLE (-4375 1075);
FORCEADD Q_RES..1
(-4950 1900);
FORCEPROP 1 LAST PART_NUMBER CS21002FB06
J 0
(-4825 1950);
DISPLAY 0.617021 (-4825 1950);
PAINT BLUE (-4825 1950);
DISPLAY INVISIBLE (-4825 1950);
FORCEPROP 1 LAST MATERIAL CHIP
J 0
(-4825 2000);
DISPLAY 0.617021 (-4825 2000);
PAINT SKYBLUE (-4825 2000);
FORCEPROP 1 LAST VALUE 1K
J 2
(-4775 1900);
DISPLAY 0.617021 (-4775 1900);
PAINT SKYBLUE (-4775 1900);
FORCEPROP 1 LAST WATTAGE 1/16W
J 2
(-4525 2000);
DISPLAY 0.617021 (-4525 2000);
PAINT SKYBLUE (-4525 2000);
FORCEPROP 1 LAST PACK_TYPE 0402LF
J 0
(-4650 1900);
DISPLAY 0.617021 (-4650 1900);
PAINT SKYBLUE (-4650 1900);
FORCEPROP 1 LAST TOLERANCE 1%
J 0
(-4750 1900);
DISPLAY 0.617021 (-4750 1900);
PAINT SKYBLUE (-4750 1900);
FORCEPROP 1 LAST LOCATION R2377
J 0
(-5175 1900);
DISPLAY 0.617021 (-5175 1900);
PAINT AQUA (-5175 1900);
FORCEPROP 1 LASTPIN (-5050 1900) $PN 1
J 0
(-5038 1912);
DISPLAY 0.617021 (-5038 1912);
PAINT MONO (-5038 1912);
FORCEPROP 1 LASTPIN (-4850 1900) $PN 2
J 0
(-4888 1912);
DISPLAY 0.617021 (-4888 1912);
PAINT MONO (-4888 1912);
FORCEPROP 1 LAST PATH I54
J 0
(-5000 2050);
DISPLAY 0.978723 (-5000 2050);
PAINT WHITE (-5000 2050);
DISPLAY INVISIBLE (-5000 2050);
FORCEPROP 2 LAST CDS_LIB pure_quanta
J 0
(-4950 1900);
DISPLAY INVISIBLE (-4950 1900);
FORCEPROP 1 LAST LOCATION R2377
J 0
(-5000 2000);
DISPLAY 1.021277 (-5000 2000);
PAINT AQUA (-5000 2000);
DISPLAY INVISIBLE (-5000 2000);
FORCEPROP 0 LAST $SEC 1
J 0
(-5000 2000);
DISPLAY 0.680851 (-5000 2000);
PAINT MONO (-5000 2000);
DISPLAY INVISIBLE (-5000 2000);
FORCEPROP 0 LAST CDS_SEC 1
J 0
(-5000 2000);
DISPLAY 1.021277 (-5000 2000);
DISPLAY INVISIBLE (-5000 2000);
FORCEADD Q_RES..1
(-4950 1750);
FORCEPROP 1 LAST PART_NUMBER CS00002JB13
J 0
(-4825 1800);
DISPLAY 0.617021 (-4825 1800);
PAINT BLUE (-4825 1800);
DISPLAY INVISIBLE (-4825 1800);
FORCEPROP 1 LAST PACK_TYPE 0402LF
J 0
(-4700 1750);
DISPLAY 0.617021 (-4700 1750);
PAINT SKYBLUE (-4700 1750);
FORCEPROP 1 LAST MATERIAL CHIP
J 0
(-4825 1850);
DISPLAY 0.617021 (-4825 1850);
PAINT SKYBLUE (-4825 1850);
FORCEPROP 1 LAST WATTAGE 1/16W
J 2
(-4525 1850);
DISPLAY 0.617021 (-4525 1850);
PAINT SKYBLUE (-4525 1850);
FORCEPROP 1 LAST TOLERANCE 5%
J 0
(-4775 1750);
DISPLAY 0.617021 (-4775 1750);
PAINT SKYBLUE (-4775 1750);
FORCEPROP 1 LAST VALUE 0
J 2
(-4800 1750);
DISPLAY 0.617021 (-4800 1750);
PAINT SKYBLUE (-4800 1750);
FORCEPROP 1 LAST LOCATION R2379
J 0
(-5175 1750);
DISPLAY 0.617021 (-5175 1750);
PAINT AQUA (-5175 1750);
FORCEPROP 1 LASTPIN (-5050 1750) $PN 1
J 0
(-5038 1762);
DISPLAY 0.617021 (-5038 1762);
PAINT MONO (-5038 1762);
FORCEPROP 1 LASTPIN (-4850 1750) $PN 2
J 0
(-4888 1762);
DISPLAY 0.617021 (-4888 1762);
PAINT MONO (-4888 1762);
FORCEPROP 1 LAST PATH I55
J 0
(-5000 1900);
DISPLAY 0.978723 (-5000 1900);
PAINT WHITE (-5000 1900);
DISPLAY INVISIBLE (-5000 1900);
FORCEPROP 2 LAST CDS_LIB pure_quanta
J 0
(-4950 1750);
DISPLAY INVISIBLE (-4950 1750);
FORCEPROP 1 LAST LOCATION R2379
J 0
(-5000 1850);
DISPLAY 1.021277 (-5000 1850);
PAINT AQUA (-5000 1850);
DISPLAY INVISIBLE (-5000 1850);
FORCEPROP 0 LAST $SEC 1
J 0
(-5000 1850);
DISPLAY 0.680851 (-5000 1850);
PAINT MONO (-5000 1850);
DISPLAY INVISIBLE (-5000 1850);
FORCEPROP 0 LAST CDS_SEC 1
J 0
(-5000 1850);
DISPLAY 1.021277 (-5000 1850);
DISPLAY INVISIBLE (-5000 1850);
FORCEADD Q_RES..1
(-4950 2150);
FORCEPROP 1 LAST PART_NUMBER CS00002JB13
J 0
(-4850 2100);
DISPLAY 0.638298 (-4850 2100);
DISPLAY INVISIBLE (-4850 2100);
FORCEPROP 1 LAST MATERIAL CHIP
J 0
(-5150 2100);
DISPLAY 0.638298 (-5150 2100);
FORCEPROP 1 LAST WATTAGE 1/16W
J 2
(-4375 2150);
DISPLAY 0.638298 (-4375 2150);
FORCEPROP 1 LAST VALUE 0
J 2
(-4825 2150);
DISPLAY 0.638298 (-4825 2150);
FORCEPROP 1 LAST PACK_TYPE 0402LF
J 0
(-4725 2150);
DISPLAY 0.638298 (-4725 2150);
FORCEPROP 1 LAST TOLERANCE 5%
J 0
(-4800 2150);
DISPLAY 0.638298 (-4800 2150);
FORCEPROP 1 LAST $LOCATION R4216
J 0
(-5175 2150);
DISPLAY 0.638298 (-5175 2150);
FORCEPROP 1 LASTPIN (-5050 2150) $PN 1
J 0
(-5038 2162);
DISPLAY 0.787234 (-5038 2162);
PAINT MONO (-5038 2162);
FORCEPROP 1 LASTPIN (-4850 2150) $PN 2
J 0
(-4888 2162);
DISPLAY 0.787234 (-4888 2162);
PAINT MONO (-4888 2162);
FORCEPROP 1 LAST PATH I56
J 0
(-5000 2300);
DISPLAY 0.978723 (-5000 2300);
PAINT WHITE (-5000 2300);
DISPLAY INVISIBLE (-5000 2300);
FORCEPROP 2 LAST CDS_LIB pure_quanta
J 0
(-4950 2150);
DISPLAY INVISIBLE (-4950 2150);
FORCEPROP 0 LAST CDS_LOCATION R4216
J 0
(-4375 2200);
DISPLAY 1.021277 (-4375 2200);
DISPLAY INVISIBLE (-4375 2200);
FORCEPROP 0 LAST $SEC 1
J 0
(-4375 2200);
DISPLAY 0.680851 (-4375 2200);
PAINT MONO (-4375 2200);
DISPLAY INVISIBLE (-4375 2200);
FORCEPROP 0 LAST CDS_SEC 1
J 0
(-4375 2200);
DISPLAY 1.021277 (-4375 2200);
DISPLAY INVISIBLE (-4375 2200);
FORCEADD Q_CAP..2
(-4150 1900);
FORCEPROP 1 LAST PART_NUMBER TMP_QCH21006JB10
J 1
(-3875 1850);
DISPLAY 0.617021 (-3875 1850);
PAINT BLUE (-3875 1850);
DISPLAY INVISIBLE (-3875 1850);
FORCEPROP 1 LAST VALUE 1000PF
J 2
(-3825 1900);
DISPLAY 0.617021 (-3825 1900);
PAINT SKYBLUE (-3825 1900);
FORCEPROP 1 LAST VOLTAGE 50V
J 0
(-3800 1900);
DISPLAY 0.617021 (-3800 1900);
PAINT SKYBLUE (-3800 1900);
FORCEPROP 1 LAST MATERIAL EMPTY
J 0
(-3675 1900);
DISPLAY 0.617021 (-3675 1900);
PAINT RED (-3675 1900);
FORCEPROP 1 LAST TOLERANCE 5%
J 2
(-3500 1850);
DISPLAY 0.617021 (-3500 1850);
PAINT SKYBLUE (-3500 1850);
FORCEPROP 1 LAST PACK_TYPE 0402
J 1
(-3625 1800);
DISPLAY 0.617021 (-3625 1800);
PAINT SKYBLUE (-3625 1800);
FORCEPROP 1 LAST LOCATION C3269
J 1
(-4350 1900);
DISPLAY 0.617021 (-4350 1900);
PAINT AQUA (-4350 1900);
FORCEPROP 1 LASTPIN (-4250 1900) $PN 1
J 0
(-4260 1915);
DISPLAY 0.617021 (-4260 1915);
PAINT MONO (-4260 1915);
FORCEPROP 1 LASTPIN (-4050 1900) $PN 2
J 0
(-4065 1915);
DISPLAY 0.617021 (-4065 1915);
PAINT MONO (-4065 1915);
FORCEPROP 1 LAST PATH I57
J 0
(-4150 2100);
DISPLAY 0.978723 (-4150 2100);
PAINT WHITE (-4150 2100);
DISPLAY INVISIBLE (-4150 2100);
FORCEPROP 2 LAST CDS_LIB pure_quanta
J 0
(-4150 1900);
DISPLAY INVISIBLE (-4150 1900);
FORCEPROP 1 LAST LOCATION C3269
J 0
(-4200 2000);
DISPLAY 1.021277 (-4200 2000);
PAINT AQUA (-4200 2000);
DISPLAY INVISIBLE (-4200 2000);
FORCEPROP 0 LAST $SEC 1
J 0
(-4200 2000);
DISPLAY 0.680851 (-4200 2000);
PAINT MONO (-4200 2000);
DISPLAY INVISIBLE (-4200 2000);
FORCEPROP 0 LAST CDS_SEC 1
J 0
(-4200 2000);
DISPLAY 1.021277 (-4200 2000);
DISPLAY INVISIBLE (-4200 2000);
FORCEADD Q_CAP..2
(-4150 2025);
FORCEPROP 1 LAST PART_NUMBER TMP_QCH21006JB10
J 1
(-3875 1975);
DISPLAY 0.617021 (-3875 1975);
PAINT BLUE (-3875 1975);
DISPLAY INVISIBLE (-3875 1975);
FORCEPROP 1 LAST VALUE 1000PF
J 2
(-3825 2025);
DISPLAY 0.617021 (-3825 2025);
PAINT SKYBLUE (-3825 2025);
FORCEPROP 1 LAST VOLTAGE 50V
J 0
(-3800 2025);
DISPLAY 0.617021 (-3800 2025);
PAINT SKYBLUE (-3800 2025);
FORCEPROP 1 LAST TOLERANCE 5%
J 2
(-3500 1975);
DISPLAY 0.617021 (-3500 1975);
PAINT SKYBLUE (-3500 1975);
FORCEPROP 1 LAST MATERIAL X7R
J 0
(-3675 2025);
DISPLAY 0.617021 (-3675 2025);
PAINT SKYBLUE (-3675 2025);
FORCEPROP 1 LAST PACK_TYPE 0402
J 1
(-3625 1925);
DISPLAY 0.617021 (-3625 1925);
PAINT SKYBLUE (-3625 1925);
FORCEPROP 1 LAST LOCATION C3268
J 1
(-4350 2025);
DISPLAY 0.617021 (-4350 2025);
PAINT AQUA (-4350 2025);
FORCEPROP 1 LASTPIN (-4250 2025) $PN 1
J 0
(-4260 2040);
DISPLAY 0.617021 (-4260 2040);
PAINT MONO (-4260 2040);
FORCEPROP 1 LASTPIN (-4050 2025) $PN 2
J 0
(-4065 2040);
DISPLAY 0.617021 (-4065 2040);
PAINT MONO (-4065 2040);
FORCEPROP 1 LAST PATH I58
J 0
(-4150 2225);
DISPLAY 0.978723 (-4150 2225);
PAINT WHITE (-4150 2225);
DISPLAY INVISIBLE (-4150 2225);
FORCEPROP 2 LAST CDS_LIB pure_quanta
J 0
(-4150 2025);
DISPLAY INVISIBLE (-4150 2025);
FORCEPROP 1 LAST LOCATION C3268
J 0
(-4200 2125);
DISPLAY 1.021277 (-4200 2125);
PAINT AQUA (-4200 2125);
DISPLAY INVISIBLE (-4200 2125);
FORCEPROP 0 LAST $SEC 1
J 0
(-4200 2125);
DISPLAY 0.680851 (-4200 2125);
PAINT MONO (-4200 2125);
DISPLAY INVISIBLE (-4200 2125);
FORCEPROP 0 LAST CDS_SEC 1
J 0
(-4200 2125);
DISPLAY 1.021277 (-4200 2125);
DISPLAY INVISIBLE (-4200 2125);
FORCEADD UNIVERSAL_GND..1
(-3700 575);
FORCEPROP 3 LASTPIN (-3700 625) SIG_NAME GND\g
J 0
(-3690 635);
DISPLAY 0.659574 (-3690 635);
PAINT MONO (-3690 635);
DISPLAY INVISIBLE (-3690 635);
FORCEPROP 1 LAST PATH I59
J 0
(-3625 575);
DISPLAY 0.872340 (-3625 575);
PAINT AQUA (-3625 575);
DISPLAY INVISIBLE (-3625 575);
FORCEPROP 2 LAST CDS_LIB logical_power
J 0
(-3700 575);
PAINT MONO (-3700 575);
DISPLAY INVISIBLE (-3700 575);
FORCEPROP 1 LAST HDL_POWER GND
J 1
(-3675 500);
DISPLAY 0.872340 (-3675 500);
PAINT GREEN (-3675 500);
DISPLAY INVISIBLE (-3675 500);
FORCEADD OFFPAGE..5
(-6150 1750);
FORCEPROP 2 LAST $XR1 253 
J 0
(-6525 1750);
DISPLAY 0.638298 (-6525 1750);
PAINT MONO (-6525 1750);
FORCEPROP 2 LAST $XR0 213 
J 0
(-6405 1750);
DISPLAY 0.638298 (-6405 1750);
PAINT MONO (-6405 1750);
FORCEPROP 2 LAST PATH I6
J 0
(-6400 1800);
DISPLAY 1.021277 (-6400 1800);
DISPLAY INVISIBLE (-6400 1800);
FORCEPROP 2 LAST CDS_LIB standard
J 0
(-6150 1750);
DISPLAY INVISIBLE (-6150 1750);
FORCEPROP 1 LAST OFFPAGE TRUE
J 0
(-5825 1625);
DISPLAY 0.872340 (-5825 1625);
PAINT GREEN (-5825 1625);
DISPLAY INVISIBLE (-5825 1625);
FORCEPROP 1 LAST COMMENT_BODY TRUE
J 0
(-6050 1675);
DISPLAY 0.872340 (-6050 1675);
PAINT GREEN (-6050 1675);
DISPLAY INVISIBLE (-6050 1675);
FORCEADD Q_RES..2
(-4050 900);
FORCEPROP 1 LAST PART_NUMBER CS21002FB06
J 0
(-4010 775);
DISPLAY 0.617021 (-4010 775);
PAINT BLUE (-4010 775);
DISPLAY INVISIBLE (-4010 775);
FORCEPROP 1 LAST PACK_TYPE 0402LF
J 0
(-4010 725);
DISPLAY 0.617021 (-4010 725);
PAINT SKYBLUE (-4010 725);
FORCEPROP 1 LAST WATTAGE 1/16W
J 0
(-4010 875);
DISPLAY 0.617021 (-4010 875);
PAINT SKYBLUE (-4010 875);
FORCEPROP 1 LAST TOLERANCE 1%
J 0
(-4005 925);
DISPLAY 0.617021 (-4005 925);
PAINT SKYBLUE (-4005 925);
FORCEPROP 1 LAST VALUE 1K
J 0
(-4005 975);
DISPLAY 0.617021 (-4005 975);
PAINT SKYBLUE (-4005 975);
FORCEPROP 1 LAST MATERIAL EMPTY
J 0
(-4010 825);
DISPLAY 0.617021 (-4010 825);
PAINT RED (-4010 825);
FORCEPROP 1 LAST LOCATION PR166
J 0
(-4005 1025);
DISPLAY 0.617021 (-4005 1025);
PAINT AQUA (-4005 1025);
FORCEPROP 1 LASTPIN (-4050 1000) $PN 1
J 0
(-4045 962);
DISPLAY 0.617021 (-4045 962);
PAINT MONO (-4045 962);
FORCEPROP 1 LASTPIN (-4050 800) $PN 2
J 0
(-4045 810);
DISPLAY 0.617021 (-4045 810);
PAINT MONO (-4045 810);
FORCEPROP 1 LAST PATH I60
J 0
(-4000 1075);
DISPLAY 0.978723 (-4000 1075);
PAINT WHITE (-4000 1075);
DISPLAY INVISIBLE (-4000 1075);
FORCEPROP 2 LAST CDS_LIB pure_quanta
J 0
(-4050 900);
DISPLAY INVISIBLE (-4050 900);
FORCEPROP 1 LAST LOCATION PR166
J 0
(-4000 1075);
DISPLAY 1.021277 (-4000 1075);
PAINT AQUA (-4000 1075);
DISPLAY INVISIBLE (-4000 1075);
FORCEPROP 0 LAST $SEC 1
J 0
(-4000 1075);
DISPLAY 0.680851 (-4000 1075);
PAINT MONO (-4000 1075);
DISPLAY INVISIBLE (-4000 1075);
FORCEPROP 0 LAST CDS_SEC 1
J 0
(-4000 1075);
DISPLAY 1.021277 (-4000 1075);
DISPLAY INVISIBLE (-4000 1075);
FORCEADD Q_CAP..1
(-3700 900);
FORCEPROP 1 LAST PART_NUMBER CH4104K1B00
J 0
(-3650 725);
DISPLAY 0.617021 (-3650 725);
PAINT BLUE (-3650 725);
DISPLAY INVISIBLE (-3650 725);
FORCEPROP 1 LAST TOLERANCE 10%
J 0
(-3650 875);
DISPLAY 0.617021 (-3650 875);
PAINT SKYBLUE (-3650 875);
FORCEPROP 1 LAST VOLTAGE 25V
J 0
(-3650 925);
DISPLAY 0.617021 (-3650 925);
PAINT SKYBLUE (-3650 925);
FORCEPROP 1 LAST VALUE 0.1UF
J 0
(-3650 975);
DISPLAY 0.617021 (-3650 975);
PAINT SKYBLUE (-3650 975);
FORCEPROP 1 LAST MATERIAL X7R
J 0
(-3650 825);
DISPLAY 0.617021 (-3650 825);
PAINT SKYBLUE (-3650 825);
FORCEPROP 1 LAST PACK_TYPE 0402
J 0
(-3650 775);
DISPLAY 0.617021 (-3650 775);
PAINT SKYBLUE (-3650 775);
FORCEPROP 1 LAST LOCATION PC330
J 0
(-3650 1025);
DISPLAY 0.617021 (-3650 1025);
PAINT AQUA (-3650 1025);
FORCEPROP 1 LASTPIN (-3700 1000) $PN 1
J 0
(-3690 980);
DISPLAY 0.617021 (-3690 980);
PAINT MONO (-3690 980);
FORCEPROP 1 LASTPIN (-3700 800) $PN 2
J 0
(-3690 780);
DISPLAY 0.617021 (-3690 780);
PAINT MONO (-3690 780);
FORCEPROP 1 LAST PATH I61
J 0
(-3650 1050);
DISPLAY 0.978723 (-3650 1050);
PAINT WHITE (-3650 1050);
DISPLAY INVISIBLE (-3650 1050);
FORCEPROP 2 LAST CDS_LIB pure_quanta
J 0
(-3700 900);
DISPLAY INVISIBLE (-3700 900);
FORCEPROP 1 LAST LOCATION PC330
J 0
(-3650 1075);
DISPLAY 1.021277 (-3650 1075);
PAINT AQUA (-3650 1075);
DISPLAY INVISIBLE (-3650 1075);
FORCEPROP 0 LAST $SEC 1
J 0
(-3650 1075);
DISPLAY 0.680851 (-3650 1075);
PAINT MONO (-3650 1075);
DISPLAY INVISIBLE (-3650 1075);
FORCEPROP 0 LAST CDS_SEC 1
J 0
(-3650 1075);
DISPLAY 1.021277 (-3650 1075);
DISPLAY INVISIBLE (-3650 1075);
FORCEADD UNIVERSAL_GND..1
(-3500 875);
FORCEPROP 3 LASTPIN (-3500 925) SIG_NAME GND\g
J 0
(-3490 935);
DISPLAY 0.659574 (-3490 935);
PAINT MONO (-3490 935);
DISPLAY INVISIBLE (-3490 935);
FORCEPROP 1 LAST PATH I62
J 0
(-3425 875);
DISPLAY 0.872340 (-3425 875);
PAINT AQUA (-3425 875);
DISPLAY INVISIBLE (-3425 875);
FORCEPROP 2 LAST CDS_LIB logical_power
J 0
(-3500 875);
PAINT MONO (-3500 875);
DISPLAY INVISIBLE (-3500 875);
FORCEPROP 1 LAST HDL_POWER GND
J 1
(-3475 800);
DISPLAY 0.872340 (-3475 800);
PAINT GREEN (-3475 800);
DISPLAY INVISIBLE (-3475 800);
FORCEADD RAA229126GNPHA0..1
(-2725 3800);
FORCEPROP 1 LAST PART_NUMBER AL229126000
J 0
(-3275 6750);
DISPLAY 0.617021 (-3275 6750);
PAINT BLUE (-3275 6750);
DISPLAY INVISIBLE (-3275 6750);
FORCEPROP 2 LAST VALUE RAA229126GNP#HA0
J 0
(-2900 6825);
DISPLAY 0.617021 (-2900 6825);
PAINT SKYBLUE (-2900 6825);
FORCEPROP 2 LAST PART_TYPE SMLF
J 0
(-2900 6875);
DISPLAY 0.638298 (-2900 6875);
FORCEPROP 1 LAST MATERIAL IC
J 0
(-3275 6675);
DISPLAY 0.617021 (-3275 6675);
PAINT SKYBLUE (-3275 6675);
FORCEPROP 1 LAST LOCATION PU14
J 0
(-3275 6825);
DISPLAY 0.617021 (-3275 6825);
PAINT AQUA (-3275 6825);
FORCEPROP 2 LASTPIN (-3425 1450) $PN 42
J 2
(-3435 1460);
DISPLAY 0.617021 (-3435 1460);
PAINT MONO (-3435 1460);
FORCEPROP 2 LASTPIN (-3425 2550) $PN 41
J 2
(-3435 2560);
DISPLAY 0.617021 (-3435 2560);
PAINT MONO (-3435 2560);
FORCEPROP 2 LASTPIN (-2075 2150) $PN 38
J 0
(-2065 2160);
DISPLAY 0.617021 (-2065 2160);
PAINT MONO (-2065 2160);
FORCEPROP 2 LASTPIN (-2075 2450) $PN 37
J 0
(-2065 2460);
DISPLAY 0.617021 (-2065 2460);
PAINT MONO (-2065 2460);
FORCEPROP 2 LASTPIN (-2075 2750) $PN 36
J 0
(-2065 2760);
DISPLAY 0.617021 (-2065 2760);
PAINT MONO (-2065 2760);
FORCEPROP 2 LASTPIN (-2075 3050) $PN 35
J 0
(-2065 3060);
DISPLAY 0.617021 (-2065 3060);
PAINT MONO (-2065 3060);
FORCEPROP 2 LASTPIN (-2075 3350) $PN 34
J 0
(-2065 3360);
DISPLAY 0.617021 (-2065 3360);
PAINT MONO (-2065 3360);
FORCEPROP 2 LASTPIN (-2075 3650) $PN 33
J 0
(-2065 3660);
DISPLAY 0.617021 (-2065 3660);
PAINT MONO (-2065 3660);
FORCEPROP 2 LASTPIN (-2075 3950) $PN 32
J 0
(-2065 3960);
DISPLAY 0.617021 (-2065 3960);
PAINT MONO (-2065 3960);
FORCEPROP 2 LASTPIN (-2075 4250) $PN 31
J 0
(-2065 4260);
DISPLAY 0.617021 (-2065 4260);
PAINT MONO (-2065 4260);
FORCEPROP 2 LASTPIN (-2075 4550) $PN 30
J 0
(-2065 4560);
DISPLAY 0.617021 (-2065 4560);
PAINT MONO (-2065 4560);
FORCEPROP 2 LASTPIN (-2075 4850) $PN 29
J 0
(-2065 4860);
DISPLAY 0.617021 (-2065 4860);
PAINT MONO (-2065 4860);
FORCEPROP 2 LASTPIN (-2075 5150) $PN 28
J 0
(-2065 5160);
DISPLAY 0.617021 (-2065 5160);
PAINT MONO (-2065 5160);
FORCEPROP 2 LASTPIN (-2075 5450) $PN 27
J 0
(-2065 5460);
DISPLAY 0.617021 (-2065 5460);
PAINT MONO (-2065 5460);
FORCEPROP 2 LASTPIN (-3425 6400) $PN 17
J 2
(-3435 6410);
DISPLAY 0.617021 (-3435 6410);
PAINT MONO (-3435 6410);
FORCEPROP 2 LASTPIN (-3425 2150) $PN 24
J 2
(-3435 2160);
DISPLAY 0.617021 (-3435 2160);
PAINT MONO (-3435 2160);
FORCEPROP 2 LASTPIN (-3425 2300) $PN 19
J 2
(-3435 2310);
DISPLAY 0.617021 (-3435 2310);
PAINT MONO (-3435 2310);
FORCEPROP 2 LASTPIN (-3425 5100) $PN 15
J 2
(-3435 5110);
DISPLAY 0.617021 (-3435 5110);
PAINT MONO (-3435 5110);
FORCEPROP 2 LASTPIN (-3425 5800) $PN 23
J 2
(-3435 5810);
DISPLAY 0.617021 (-3435 5810);
PAINT MONO (-3435 5810);
FORCEPROP 2 LASTPIN (-3425 2700) $PN 18
J 2
(-3435 2710);
DISPLAY 0.617021 (-3435 2710);
PAINT MONO (-3435 2710);
FORCEPROP 2 LASTPIN (-3425 6550) $PN 16
J 2
(-3435 6560);
DISPLAY 0.617021 (-3435 6560);
PAINT MONO (-3435 6560);
FORCEPROP 2 LASTPIN (-3425 1750) $PN 20
J 2
(-3435 1760);
DISPLAY 0.617021 (-3435 1760);
PAINT MONO (-3435 1760);
FORCEPROP 2 LASTPIN (-3425 5400) $PN 14
J 2
(-3435 5410);
DISPLAY 0.617021 (-3435 5410);
PAINT MONO (-3435 5410);
FORCEPROP 2 LASTPIN (-3425 5250) $PN 13
J 2
(-3435 5260);
DISPLAY 0.617021 (-3435 5260);
PAINT MONO (-3435 5260);
FORCEPROP 2 LASTPIN (-2075 2250) $PN 1
J 0
(-2065 2260);
DISPLAY 0.617021 (-2065 2260);
PAINT MONO (-2065 2260);
FORCEPROP 2 LASTPIN (-2075 2550) $PN 2
J 0
(-2065 2560);
DISPLAY 0.617021 (-2065 2560);
PAINT MONO (-2065 2560);
FORCEPROP 2 LASTPIN (-2075 2850) $PN 3
J 0
(-2065 2860);
DISPLAY 0.617021 (-2065 2860);
PAINT MONO (-2065 2860);
FORCEPROP 2 LASTPIN (-2075 3150) $PN 4
J 0
(-2065 3160);
DISPLAY 0.617021 (-2065 3160);
PAINT MONO (-2065 3160);
FORCEPROP 2 LASTPIN (-2075 3450) $PN 5
J 0
(-2065 3460);
DISPLAY 0.617021 (-2065 3460);
PAINT MONO (-2065 3460);
FORCEPROP 2 LASTPIN (-2075 3750) $PN 6
J 0
(-2065 3760);
DISPLAY 0.617021 (-2065 3760);
PAINT MONO (-2065 3760);
FORCEPROP 2 LASTPIN (-2075 4050) $PN 7
J 0
(-2065 4060);
DISPLAY 0.617021 (-2065 4060);
PAINT MONO (-2065 4060);
FORCEPROP 2 LASTPIN (-2075 4350) $PN 8
J 0
(-2065 4360);
DISPLAY 0.617021 (-2065 4360);
PAINT MONO (-2065 4360);
FORCEPROP 2 LASTPIN (-2075 4650) $PN 9
J 0
(-2065 4660);
DISPLAY 0.617021 (-2065 4660);
PAINT MONO (-2065 4660);
FORCEPROP 2 LASTPIN (-2075 4950) $PN 10
J 0
(-2065 4960);
DISPLAY 0.617021 (-2065 4960);
PAINT MONO (-2065 4960);
FORCEPROP 2 LASTPIN (-2075 5250) $PN 11
J 0
(-2065 5260);
DISPLAY 0.617021 (-2065 5260);
PAINT MONO (-2065 5260);
FORCEPROP 2 LASTPIN (-2075 5550) $PN 12
J 0
(-2065 5560);
DISPLAY 0.617021 (-2065 5560);
PAINT MONO (-2065 5560);
FORCEPROP 2 LASTPIN (-3425 4250) $PN 26
J 2
(-3435 4260);
DISPLAY 0.617021 (-3435 4260);
PAINT MONO (-3435 4260);
FORCEPROP 2 LASTPIN (-3425 3150) $PN 39
J 2
(-3435 3160);
DISPLAY 0.617021 (-3435 3160);
PAINT MONO (-3435 3160);
FORCEPROP 2 LASTPIN (-3425 6100) $PN 21
J 2
(-3435 6110);
DISPLAY 0.617021 (-3435 6110);
PAINT MONO (-3435 6110);
FORCEPROP 2 LASTPIN (-3425 5950) $PN 22
J 2
(-3435 5960);
DISPLAY 0.617021 (-3435 5960);
PAINT MONO (-3435 5960);
FORCEPROP 2 LASTPIN (-2075 1350) $PN 43
J 0
(-2065 1360);
DISPLAY 0.617021 (-2065 1360);
PAINT MONO (-2065 1360);
FORCEPROP 2 LASTPIN (-2075 1650) $PN 44
J 0
(-2065 1660);
DISPLAY 0.617021 (-2065 1660);
PAINT MONO (-2065 1660);
FORCEPROP 2 LASTPIN (-3425 1000) $PN TH
J 2
(-3435 1010);
DISPLAY 0.617021 (-3435 1010);
PAINT MONO (-3435 1010);
FORCEPROP 2 LASTPIN (-2075 6550) $PN 47
J 0
(-2065 6560);
DISPLAY 0.617021 (-2065 6560);
PAINT MONO (-2065 6560);
FORCEPROP 2 LASTPIN (-2075 6250) $PN 48
J 0
(-2065 6260);
DISPLAY 0.617021 (-2065 6260);
PAINT MONO (-2065 6260);
FORCEPROP 2 LASTPIN (-3425 1100) $PN 46
J 2
(-3435 1110);
DISPLAY 0.617021 (-3435 1110);
PAINT MONO (-3435 1110);
FORCEPROP 2 LASTPIN (-3425 1200) $PN 45
J 2
(-3435 1210);
DISPLAY 0.617021 (-3435 1210);
PAINT MONO (-3435 1210);
FORCEPROP 2 LASTPIN (-3425 4500) $PN 25
J 2
(-3435 4510);
DISPLAY 0.617021 (-3435 4510);
PAINT MONO (-3435 4510);
FORCEPROP 2 LASTPIN (-3425 3400) $PN 40
J 2
(-3435 3410);
DISPLAY 0.617021 (-3435 3410);
PAINT MONO (-3435 3410);
FORCEPROP 1 LAST PATH I63
J 0
(-2725 3800);
DISPLAY 0.723404 (-2725 3800);
PAINT GREEN (-2725 3800);
DISPLAY INVISIBLE (-2725 3800);
FORCEPROP 1 LAST NEEDS_NO_SIZE TRUE
J 0
(-2725 3800);
DISPLAY 0.723404 (-2725 3800);
PAINT GREEN (-2725 3800);
DISPLAY INVISIBLE (-2725 3800);
FORCEPROP 1 LAST CDS_LMAN_SYM_OUTLINE -550,2850,500,-2850
J 0
(-2725 3800);
DISPLAY 0.468085 (-2725 3800);
PAINT GREEN (-2725 3800);
DISPLAY INVISIBLE (-2725 3800);
FORCEPROP 2 LAST CDS_LIB pure_quanta
J 0
(-2725 3800);
DISPLAY INVISIBLE (-2725 3800);
FORCEPROP 2 LAST SEC_TYPE 
J 0
(-2900 6925);
DISPLAY 1.021277 (-2900 6925);
DISPLAY INVISIBLE (-2900 6925);
FORCEPROP 2 LAST SEC 1
J 0
(-2900 6925);
DISPLAY 0.680851 (-2900 6925);
PAINT MONO (-2900 6925);
DISPLAY INVISIBLE (-2900 6925);
FORCEADD UNIVERSAL_GND..1
R 1
(-3450 1900);
FORCEPROP 3 LASTPIN (-3500 1900) SIG_NAME GND\g
J 0
(-3490 1910);
DISPLAY 0.659574 (-3490 1910);
PAINT MONO (-3490 1910);
DISPLAY INVISIBLE (-3490 1910);
FORCEPROP 1 LAST PATH I64
R 1
J 0
(-3450 1975);
DISPLAY 0.872340 (-3450 1975);
PAINT AQUA (-3450 1975);
DISPLAY INVISIBLE (-3450 1975);
FORCEPROP 2 LAST CDS_LIB logical_power
J 0
(-3450 1900);
PAINT MONO (-3450 1900);
DISPLAY INVISIBLE (-3450 1900);
FORCEPROP 1 LAST HDL_POWER GND
R 1
J 1
(-3375 1925);
DISPLAY 0.872340 (-3375 1925);
PAINT GREEN (-3375 1925);
DISPLAY INVISIBLE (-3375 1925);
FORCEADD UNIVERSAL_GND..1
R 1
(-3450 2025);
FORCEPROP 3 LASTPIN (-3500 2025) SIG_NAME GND\g
J 0
(-3490 2035);
DISPLAY 0.659574 (-3490 2035);
PAINT MONO (-3490 2035);
DISPLAY INVISIBLE (-3490 2035);
FORCEPROP 1 LAST PATH I65
R 1
J 0
(-3450 2100);
DISPLAY 0.872340 (-3450 2100);
PAINT AQUA (-3450 2100);
DISPLAY INVISIBLE (-3450 2100);
FORCEPROP 2 LAST CDS_LIB logical_power
J 0
(-3450 2025);
PAINT MONO (-3450 2025);
DISPLAY INVISIBLE (-3450 2025);
FORCEPROP 1 LAST HDL_POWER GND
R 1
J 1
(-3375 2050);
DISPLAY 0.872340 (-3375 2050);
PAINT GREEN (-3375 2050);
DISPLAY INVISIBLE (-3375 2050);
FORCEADD Q_RES..1
(-4600 2700);
FORCEPROP 1 LAST PART_NUMBER CS00002JB13
J 0
(-4700 2750);
DISPLAY 0.489362 (-4700 2750);
PAINT BLUE (-4700 2750);
DISPLAY INVISIBLE (-4700 2750);
FORCEPROP 1 LAST VALUE 0
J 2
(-4450 2700);
DISPLAY 0.489362 (-4450 2700);
PAINT SKYBLUE (-4450 2700);
FORCEPROP 1 LAST WATTAGE 1/16W
J 2
(-4425 2800);
DISPLAY 0.489362 (-4425 2800);
PAINT SKYBLUE (-4425 2800);
FORCEPROP 1 LAST TOLERANCE 5%
J 0
(-4425 2700);
DISPLAY 0.489362 (-4425 2700);
PAINT SKYBLUE (-4425 2700);
FORCEPROP 1 LAST MATERIAL CHIP
J 0
(-4350 2700);
DISPLAY 0.489362 (-4350 2700);
PAINT SKYBLUE (-4350 2700);
FORCEPROP 1 LAST PACK_TYPE 0402LF
J 0
(-4700 2800);
DISPLAY 0.489362 (-4700 2800);
PAINT SKYBLUE (-4700 2800);
FORCEPROP 1 LAST LOCATION R4593
J 0
(-4825 2700);
DISPLAY 0.617021 (-4825 2700);
PAINT AQUA (-4825 2700);
FORCEPROP 1 LASTPIN (-4700 2700) $PN 1
J 0
(-4688 2712);
DISPLAY 0.787234 (-4688 2712);
PAINT MONO (-4688 2712);
FORCEPROP 1 LASTPIN (-4500 2700) $PN 2
J 0
(-4538 2712);
DISPLAY 0.787234 (-4538 2712);
PAINT MONO (-4538 2712);
FORCEPROP 1 LAST PATH I66
J 0
(-4650 2850);
DISPLAY 0.978723 (-4650 2850);
PAINT WHITE (-4650 2850);
DISPLAY INVISIBLE (-4650 2850);
FORCEPROP 2 LAST CDS_LIB pure_quanta
J 0
(-4600 2700);
DISPLAY INVISIBLE (-4600 2700);
FORCEPROP 0 LAST $SEC 1
J 0
(-4425 2825);
DISPLAY 0.680851 (-4425 2825);
PAINT MONO (-4425 2825);
DISPLAY INVISIBLE (-4425 2825);
FORCEPROP 0 LAST CDS_SEC 1
J 0
(-4425 2825);
DISPLAY 1.021277 (-4425 2825);
DISPLAY INVISIBLE (-4425 2825);
FORCEADD Q_CAP..1
(-4275 3275);
FORCEPROP 1 LAST PART_NUMBER TMP_QCH2336K1B12
J 0
(-4225 3100);
DISPLAY 0.617021 (-4225 3100);
PAINT BLUE (-4225 3100);
DISPLAY INVISIBLE (-4225 3100);
FORCEPROP 1 LAST VALUE 3300PF
J 0
(-4225 3350);
DISPLAY 0.617021 (-4225 3350);
PAINT SKYBLUE (-4225 3350);
FORCEPROP 1 LAST VOLTAGE 50V
J 0
(-4225 3300);
DISPLAY 0.617021 (-4225 3300);
PAINT SKYBLUE (-4225 3300);
FORCEPROP 1 LAST TOLERANCE 10%
J 0
(-4225 3250);
DISPLAY 0.617021 (-4225 3250);
PAINT SKYBLUE (-4225 3250);
FORCEPROP 1 LAST MATERIAL X7R
J 0
(-4225 3200);
DISPLAY 0.617021 (-4225 3200);
PAINT SKYBLUE (-4225 3200);
FORCEPROP 1 LAST PACK_TYPE 0402
J 0
(-4225 3150);
DISPLAY 0.617021 (-4225 3150);
PAINT SKYBLUE (-4225 3150);
FORCEPROP 1 LAST LOCATION PC594
J 0
(-4225 3400);
DISPLAY 0.617021 (-4225 3400);
PAINT AQUA (-4225 3400);
FORCEPROP 1 LASTPIN (-4275 3375) $PN 1
J 0
(-4265 3355);
DISPLAY 0.617021 (-4265 3355);
PAINT MONO (-4265 3355);
FORCEPROP 1 LASTPIN (-4275 3175) $PN 2
J 0
(-4265 3155);
DISPLAY 0.617021 (-4265 3155);
PAINT MONO (-4265 3155);
FORCEPROP 1 LAST PATH I67
J 0
(-4225 3425);
DISPLAY 0.978723 (-4225 3425);
PAINT WHITE (-4225 3425);
DISPLAY INVISIBLE (-4225 3425);
FORCEPROP 2 LAST CDS_LIB pure_quanta
J 0
(-4275 3275);
DISPLAY INVISIBLE (-4275 3275);
FORCEPROP 1 LAST LOCATION PC594
J 0
(-4225 3400);
DISPLAY 1.021277 (-4225 3400);
PAINT AQUA (-4225 3400);
DISPLAY INVISIBLE (-4225 3400);
FORCEPROP 0 LAST $SEC 1
J 0
(-4225 3400);
DISPLAY 0.680851 (-4225 3400);
PAINT MONO (-4225 3400);
DISPLAY INVISIBLE (-4225 3400);
FORCEPROP 0 LAST CDS_SEC 1
J 0
(-4225 3400);
DISPLAY 1.021277 (-4225 3400);
DISPLAY INVISIBLE (-4225 3400);
FORCEADD Q_RES..1
(-4725 3450);
FORCEPROP 1 LAST PART_NUMBER CS00002JB13
J 0
(-4600 3500);
DISPLAY 0.617021 (-4600 3500);
PAINT BLUE (-4600 3500);
DISPLAY INVISIBLE (-4600 3500);
FORCEPROP 1 LAST MATERIAL CHIP
J 0
(-4600 3550);
DISPLAY 0.617021 (-4600 3550);
PAINT SKYBLUE (-4600 3550);
FORCEPROP 1 LAST WATTAGE 1/16W
J 2
(-4300 3550);
DISPLAY 0.617021 (-4300 3550);
PAINT SKYBLUE (-4300 3550);
FORCEPROP 1 LAST PACK_TYPE 0402LF
J 0
(-4475 3450);
DISPLAY 0.617021 (-4475 3450);
PAINT SKYBLUE (-4475 3450);
FORCEPROP 1 LAST VALUE 0
J 2
(-4575 3450);
DISPLAY 0.617021 (-4575 3450);
PAINT SKYBLUE (-4575 3450);
FORCEPROP 1 LAST TOLERANCE 5%
J 0
(-4550 3450);
DISPLAY 0.617021 (-4550 3450);
PAINT SKYBLUE (-4550 3450);
FORCEPROP 1 LAST LOCATION PR345
J 0
(-4925 3450);
DISPLAY 0.617021 (-4925 3450);
PAINT AQUA (-4925 3450);
FORCEPROP 1 LASTPIN (-4825 3450) $PN 1
J 0
(-4813 3462);
DISPLAY 0.617021 (-4813 3462);
PAINT MONO (-4813 3462);
FORCEPROP 1 LASTPIN (-4625 3450) $PN 2
J 0
(-4663 3462);
DISPLAY 0.617021 (-4663 3462);
PAINT MONO (-4663 3462);
FORCEPROP 1 LAST PATH I68
J 0
(-4775 3600);
DISPLAY 0.978723 (-4775 3600);
PAINT WHITE (-4775 3600);
DISPLAY INVISIBLE (-4775 3600);
FORCEPROP 2 LAST CDS_LIB pure_quanta
J 0
(-4725 3450);
DISPLAY INVISIBLE (-4725 3450);
FORCEPROP 1 LAST LOCATION PR345
J 0
(-4775 3550);
DISPLAY 1.021277 (-4775 3550);
PAINT AQUA (-4775 3550);
DISPLAY INVISIBLE (-4775 3550);
FORCEPROP 0 LAST $SEC 1
J 0
(-4775 3550);
DISPLAY 0.680851 (-4775 3550);
PAINT MONO (-4775 3550);
DISPLAY INVISIBLE (-4775 3550);
FORCEPROP 0 LAST CDS_SEC 1
J 0
(-4775 3550);
DISPLAY 1.021277 (-4775 3550);
DISPLAY INVISIBLE (-4775 3550);
FORCEADD UNIVERSAL_GND..1
(-1800 900);
FORCEPROP 3 LASTPIN (-1800 950) SIG_NAME GND\g
J 0
(-1790 960);
DISPLAY 0.659574 (-1790 960);
PAINT MONO (-1790 960);
DISPLAY INVISIBLE (-1790 960);
FORCEPROP 1 LAST PATH I69
J 0
(-1725 900);
DISPLAY 0.872340 (-1725 900);
PAINT AQUA (-1725 900);
DISPLAY INVISIBLE (-1725 900);
FORCEPROP 2 LAST CDS_LIB logical_power
J 0
(-1800 900);
PAINT MONO (-1800 900);
DISPLAY INVISIBLE (-1800 900);
FORCEPROP 1 LAST HDL_POWER GND
J 1
(-1775 825);
DISPLAY 0.872340 (-1775 825);
PAINT GREEN (-1775 825);
DISPLAY INVISIBLE (-1775 825);
FORCEADD OFFPAGE..1
(-6150 2150);
FORCEPROP 2 LAST $XR0 222 
J 0
(-6402 2150);
DISPLAY 0.638298 (-6402 2150);
PAINT MONO (-6402 2150);
FORCEPROP 2 LAST PATH I7
J 0
(-6400 2200);
DISPLAY 1.021277 (-6400 2200);
DISPLAY INVISIBLE (-6400 2200);
FORCEPROP 2 LAST CDS_LIB standard
J 0
(-6150 2150);
DISPLAY INVISIBLE (-6150 2150);
FORCEPROP 1 LAST OFFPAGE TRUE
J 0
(-5825 2025);
DISPLAY 0.872340 (-5825 2025);
PAINT GREEN (-5825 2025);
DISPLAY INVISIBLE (-5825 2025);
FORCEPROP 1 LAST COMMENT_BODY TRUE
J 0
(-6025 2050);
DISPLAY 0.872340 (-6025 2050);
PAINT GREEN (-6025 2050);
DISPLAY INVISIBLE (-6025 2050);
FORCEADD Q_CAP..1
(-1800 1150);
FORCEPROP 1 LAST PART_NUMBER TMP_QCH14706KB18
J 0
(-1750 950);
DISPLAY 0.617021 (-1750 950);
PAINT BLUE (-1750 950);
DISPLAY INVISIBLE (-1750 950);
FORCEPROP 1 LAST VOLTAGE 50V
J 0
(-1750 1150);
DISPLAY 0.617021 (-1750 1150);
PAINT SKYBLUE (-1750 1150);
FORCEPROP 1 LAST TOLERANCE 10%
J 0
(-1750 1100);
DISPLAY 0.617021 (-1750 1100);
PAINT SKYBLUE (-1750 1100);
FORCEPROP 1 LAST PACK_TYPE 0402
J 0
(-1750 1000);
DISPLAY 0.617021 (-1750 1000);
PAINT SKYBLUE (-1750 1000);
FORCEPROP 1 LAST MATERIAL X7R
J 0
(-1750 1050);
DISPLAY 0.617021 (-1750 1050);
PAINT SKYBLUE (-1750 1050);
FORCEPROP 1 LAST VALUE 470PF
J 0
(-1750 1200);
DISPLAY 0.617021 (-1750 1200);
PAINT SKYBLUE (-1750 1200);
FORCEPROP 1 LAST LOCATION PC336
J 0
(-1750 1250);
DISPLAY 0.617021 (-1750 1250);
PAINT AQUA (-1750 1250);
FORCEPROP 1 LASTPIN (-1800 1250) $PN 1
J 0
(-1790 1230);
DISPLAY 0.617021 (-1790 1230);
PAINT MONO (-1790 1230);
FORCEPROP 1 LASTPIN (-1800 1050) $PN 2
J 0
(-1790 1030);
DISPLAY 0.617021 (-1790 1030);
PAINT MONO (-1790 1030);
FORCEPROP 1 LAST PATH I70
J 0
(-1750 1300);
DISPLAY 0.978723 (-1750 1300);
PAINT WHITE (-1750 1300);
DISPLAY INVISIBLE (-1750 1300);
FORCEPROP 2 LAST CDS_LIB pure_quanta
J 0
(-1800 1150);
DISPLAY INVISIBLE (-1800 1150);
FORCEPROP 1 LAST LOCATION PC336
J 0
(-1750 1300);
DISPLAY 1.021277 (-1750 1300);
PAINT AQUA (-1750 1300);
DISPLAY INVISIBLE (-1750 1300);
FORCEPROP 0 LAST $SEC 1
J 0
(-1750 1300);
DISPLAY 0.680851 (-1750 1300);
PAINT MONO (-1750 1300);
DISPLAY INVISIBLE (-1750 1300);
FORCEPROP 0 LAST CDS_SEC 1
J 0
(-1750 1300);
DISPLAY 1.021277 (-1750 1300);
DISPLAY INVISIBLE (-1750 1300);
FORCEADD UNIVERSAL_GND..1
(-1175 900);
FORCEPROP 3 LASTPIN (-1175 950) SIG_NAME GND\g
J 0
(-1165 960);
DISPLAY 0.659574 (-1165 960);
PAINT MONO (-1165 960);
DISPLAY INVISIBLE (-1165 960);
FORCEPROP 1 LAST PATH I71
J 0
(-1100 900);
DISPLAY 0.872340 (-1100 900);
PAINT AQUA (-1100 900);
DISPLAY INVISIBLE (-1100 900);
FORCEPROP 2 LAST CDS_LIB logical_power
J 0
(-1175 900);
DISPLAY INVISIBLE (-1175 900);
FORCEPROP 1 LAST HDL_POWER GND
J 1
(-1150 825);
DISPLAY 0.872340 (-1150 825);
PAINT GREEN (-1150 825);
DISPLAY INVISIBLE (-1150 825);
FORCEADD Q_RES..2
(-1175 1150);
FORCEPROP 1 LAST PART_NUMBER CS31002FB08
J 0
(-1135 1025);
DISPLAY 0.617021 (-1135 1025);
PAINT BLUE (-1135 1025);
DISPLAY INVISIBLE (-1135 1025);
FORCEPROP 1 LAST WATTAGE 1/16W
J 0
(-1135 1125);
DISPLAY 0.617021 (-1135 1125);
PAINT SKYBLUE (-1135 1125);
FORCEPROP 1 LAST PACK_TYPE 0402LF
J 0
(-1135 975);
DISPLAY 0.617021 (-1135 975);
PAINT SKYBLUE (-1135 975);
FORCEPROP 1 LAST TOLERANCE 1%
J 0
(-1130 1175);
DISPLAY 0.617021 (-1130 1175);
PAINT SKYBLUE (-1130 1175);
FORCEPROP 1 LAST VALUE 10K
J 0
(-1130 1225);
DISPLAY 0.617021 (-1130 1225);
PAINT SKYBLUE (-1130 1225);
FORCEPROP 1 LAST MATERIAL EMPTY
J 0
(-1135 1075);
DISPLAY 0.617021 (-1135 1075);
PAINT RED (-1135 1075);
FORCEPROP 1 LAST LOCATION PR400
J 0
(-1130 1275);
DISPLAY 0.617021 (-1130 1275);
PAINT AQUA (-1130 1275);
FORCEPROP 1 LAST PATH I72
J 0
(-1125 1325);
DISPLAY 0.978723 (-1125 1325);
PAINT WHITE (-1125 1325);
DISPLAY INVISIBLE (-1125 1325);
FORCEPROP 2 LAST CDS_LIB pure_quanta
J 0
(-1175 1150);
DISPLAY INVISIBLE (-1175 1150);
FORCEPROP 0 LAST $SEC 1
J 0
(-1125 1325);
DISPLAY INVISIBLE (-1125 1325);
FORCEPROP 0 LAST CDS_SEC 1
J 0
(-1125 1325);
DISPLAY INVISIBLE (-1125 1325);
FORCEPROP 1 LASTPIN (-1175 1250) $PN 1
J 0
(-1170 1212);
DISPLAY 0.787234 (-1170 1212);
PAINT MONO (-1170 1212);
DISPLAY INVISIBLE (-1170 1212);
FORCEPROP 1 LASTPIN (-1175 1050) $PN 2
J 0
(-1170 1060);
DISPLAY 0.787234 (-1170 1060);
PAINT MONO (-1170 1060);
DISPLAY INVISIBLE (-1170 1060);
FORCEADD Q_RES..1
(-1725 2675);
FORCEPROP 1 LAST PART_NUMBER CS00002JB13
J 0
(-1625 2625);
DISPLAY 0.638298 (-1625 2625);
DISPLAY INVISIBLE (-1625 2625);
FORCEPROP 1 LAST VALUE 0
J 2
(-1600 2675);
DISPLAY 0.638298 (-1600 2675);
FORCEPROP 1 LAST TOLERANCE 5%
J 0
(-1575 2675);
DISPLAY 0.638298 (-1575 2675);
FORCEPROP 1 LAST MATERIAL EMPTY
J 0
(-1925 2625);
DISPLAY 0.638298 (-1925 2625);
FORCEPROP 1 LAST PACK_TYPE 0402LF
J 0
(-1500 2675);
DISPLAY 0.638298 (-1500 2675);
FORCEPROP 1 LAST WATTAGE 1/16W
J 2
(-1150 2675);
DISPLAY 0.638298 (-1150 2675);
FORCEPROP 1 LAST LOCATION PR4218
J 0
(-1950 2675);
DISPLAY 0.638298 (-1950 2675);
FORCEPROP 1 LASTPIN (-1825 2675) $PN 1
J 0
(-1813 2687);
DISPLAY 0.787234 (-1813 2687);
PAINT MONO (-1813 2687);
FORCEPROP 1 LASTPIN (-1625 2675) $PN 2
J 0
(-1663 2687);
DISPLAY 0.787234 (-1663 2687);
PAINT MONO (-1663 2687);
FORCEPROP 1 LAST PATH I73
J 0
(-1775 2825);
DISPLAY 0.978723 (-1775 2825);
PAINT WHITE (-1775 2825);
DISPLAY INVISIBLE (-1775 2825);
FORCEPROP 2 LAST CDS_LIB pure_quanta
J 0
(-1725 2675);
DISPLAY INVISIBLE (-1725 2675);
FORCEPROP 0 LAST $SEC 1
J 0
(-1150 2725);
DISPLAY 0.680851 (-1150 2725);
PAINT MONO (-1150 2725);
DISPLAY INVISIBLE (-1150 2725);
FORCEPROP 0 LAST CDS_SEC 1
J 0
(-1150 2725);
DISPLAY 1.021277 (-1150 2725);
DISPLAY INVISIBLE (-1150 2725);
FORCEADD Q_RES..1
(-1725 2975);
FORCEPROP 1 LAST PART_NUMBER CS00002JB13
J 0
(-1625 2925);
DISPLAY 0.638298 (-1625 2925);
DISPLAY INVISIBLE (-1625 2925);
FORCEPROP 1 LAST PACK_TYPE 0402LF
J 0
(-1500 2975);
DISPLAY 0.638298 (-1500 2975);
FORCEPROP 1 LAST WATTAGE 1/16W
J 2
(-1150 2975);
DISPLAY 0.638298 (-1150 2975);
FORCEPROP 1 LAST VALUE 0
J 2
(-1600 2975);
DISPLAY 0.638298 (-1600 2975);
FORCEPROP 1 LAST TOLERANCE 5%
J 0
(-1575 2975);
DISPLAY 0.638298 (-1575 2975);
FORCEPROP 1 LAST MATERIAL EMPTY
J 0
(-1925 2925);
DISPLAY 0.638298 (-1925 2925);
FORCEPROP 1 LAST LOCATION PR4217
J 0
(-1950 2975);
DISPLAY 0.638298 (-1950 2975);
FORCEPROP 1 LASTPIN (-1825 2975) $PN 1
J 0
(-1813 2987);
DISPLAY 0.787234 (-1813 2987);
PAINT MONO (-1813 2987);
FORCEPROP 1 LASTPIN (-1625 2975) $PN 2
J 0
(-1663 2987);
DISPLAY 0.787234 (-1663 2987);
PAINT MONO (-1663 2987);
FORCEPROP 1 LAST PATH I74
J 0
(-1775 3125);
DISPLAY 0.978723 (-1775 3125);
PAINT WHITE (-1775 3125);
DISPLAY INVISIBLE (-1775 3125);
FORCEPROP 2 LAST CDS_LIB pure_quanta
J 0
(-1725 2975);
DISPLAY INVISIBLE (-1725 2975);
FORCEPROP 0 LAST $SEC 1
J 0
(-1150 3025);
DISPLAY 0.680851 (-1150 3025);
PAINT MONO (-1150 3025);
DISPLAY INVISIBLE (-1150 3025);
FORCEPROP 0 LAST CDS_SEC 1
J 0
(-1150 3025);
DISPLAY 1.021277 (-1150 3025);
DISPLAY INVISIBLE (-1150 3025);
FORCEADD UNIVERSAL_GND..1
(-1100 2600);
FORCEPROP 3 LASTPIN (-1100 2650) SIG_NAME GND\g
J 0
(-1090 2660);
DISPLAY 0.659574 (-1090 2660);
PAINT MONO (-1090 2660);
DISPLAY INVISIBLE (-1090 2660);
FORCEPROP 1 LAST PATH I75
J 0
(-1025 2600);
DISPLAY 0.872340 (-1025 2600);
PAINT AQUA (-1025 2600);
DISPLAY INVISIBLE (-1025 2600);
FORCEPROP 2 LAST CDS_LIB logical_power
J 0
(-1100 2600);
DISPLAY INVISIBLE (-1100 2600);
FORCEPROP 1 LAST HDL_POWER GND
J 1
(-1075 2525);
DISPLAY 0.872340 (-1075 2525);
PAINT GREEN (-1075 2525);
DISPLAY INVISIBLE (-1075 2525);
FORCEADD UNIVERSAL_GND..1
(-1100 2900);
FORCEPROP 3 LASTPIN (-1100 2950) SIG_NAME GND\g
J 0
(-1090 2960);
DISPLAY 0.659574 (-1090 2960);
PAINT MONO (-1090 2960);
DISPLAY INVISIBLE (-1090 2960);
FORCEPROP 1 LAST PATH I76
J 0
(-1025 2900);
DISPLAY 0.872340 (-1025 2900);
PAINT AQUA (-1025 2900);
DISPLAY INVISIBLE (-1025 2900);
FORCEPROP 2 LAST CDS_LIB logical_power
J 0
(-1100 2900);
DISPLAY INVISIBLE (-1100 2900);
FORCEPROP 1 LAST HDL_POWER GND
J 1
(-1075 2825);
DISPLAY 0.872340 (-1075 2825);
PAINT GREEN (-1075 2825);
DISPLAY INVISIBLE (-1075 2825);
FORCEADD Q_RES..1
(-4775 4550);
FORCEPROP 1 LAST PART_NUMBER CS00002JB13
J 0
(-4650 4600);
DISPLAY 0.617021 (-4650 4600);
PAINT BLUE (-4650 4600);
DISPLAY INVISIBLE (-4650 4600);
FORCEPROP 1 LAST VALUE 0
J 2
(-4625 4550);
DISPLAY 0.617021 (-4625 4550);
PAINT SKYBLUE (-4625 4550);
FORCEPROP 1 LAST TOLERANCE 5%
J 0
(-4600 4550);
DISPLAY 0.617021 (-4600 4550);
PAINT SKYBLUE (-4600 4550);
FORCEPROP 1 LAST MATERIAL CHIP
J 0
(-4650 4650);
DISPLAY 0.617021 (-4650 4650);
PAINT SKYBLUE (-4650 4650);
FORCEPROP 1 LAST PACK_TYPE 0402LF
J 0
(-4525 4550);
DISPLAY 0.617021 (-4525 4550);
PAINT SKYBLUE (-4525 4550);
FORCEPROP 1 LAST WATTAGE 1/16W
J 2
(-4350 4650);
DISPLAY 0.617021 (-4350 4650);
PAINT SKYBLUE (-4350 4650);
FORCEPROP 1 LAST LOCATION PR170
J 0
(-4975 4550);
DISPLAY 0.617021 (-4975 4550);
PAINT AQUA (-4975 4550);
FORCEPROP 1 LASTPIN (-4875 4550) $PN 1
J 0
(-4863 4562);
DISPLAY 0.617021 (-4863 4562);
PAINT MONO (-4863 4562);
FORCEPROP 1 LASTPIN (-4675 4550) $PN 2
J 0
(-4713 4562);
DISPLAY 0.617021 (-4713 4562);
PAINT MONO (-4713 4562);
FORCEPROP 1 LAST PATH I77
J 0
(-4825 4700);
DISPLAY 0.978723 (-4825 4700);
PAINT WHITE (-4825 4700);
DISPLAY INVISIBLE (-4825 4700);
FORCEPROP 2 LAST CDS_LIB pure_quanta
J 0
(-4775 4550);
DISPLAY INVISIBLE (-4775 4550);
FORCEPROP 1 LAST LOCATION PR170
J 0
(-4825 4650);
DISPLAY 1.021277 (-4825 4650);
PAINT AQUA (-4825 4650);
DISPLAY INVISIBLE (-4825 4650);
FORCEPROP 0 LAST $SEC 1
J 0
(-4825 4650);
DISPLAY 0.680851 (-4825 4650);
PAINT MONO (-4825 4650);
DISPLAY INVISIBLE (-4825 4650);
FORCEPROP 0 LAST CDS_SEC 1
J 0
(-4825 4650);
DISPLAY 1.021277 (-4825 4650);
DISPLAY INVISIBLE (-4825 4650);
FORCEADD Q_RES..1
(-4800 5250);
FORCEPROP 1 LAST PART_NUMBER CS03322FB03
J 0
(-4675 5300);
DISPLAY 0.617021 (-4675 5300);
PAINT BLUE (-4675 5300);
DISPLAY INVISIBLE (-4675 5300);
FORCEPROP 1 LAST VALUE 33.2
J 2
(-4650 5250);
DISPLAY 0.617021 (-4650 5250);
PAINT SKYBLUE (-4650 5250);
FORCEPROP 1 LAST MATERIAL CHIP
J 0
(-4675 5350);
DISPLAY 0.617021 (-4675 5350);
PAINT SKYBLUE (-4675 5350);
FORCEPROP 1 LAST WATTAGE 1/16W
J 2
(-4425 5350);
DISPLAY 0.617021 (-4425 5350);
PAINT SKYBLUE (-4425 5350);
FORCEPROP 1 LAST PACK_TYPE 0402LF
J 0
(-4550 5250);
DISPLAY 0.617021 (-4550 5250);
PAINT SKYBLUE (-4550 5250);
FORCEPROP 1 LAST TOLERANCE 1%
J 0
(-4625 5250);
DISPLAY 0.617021 (-4625 5250);
PAINT SKYBLUE (-4625 5250);
FORCEPROP 1 LAST LOCATION R2372
J 0
(-5050 5250);
DISPLAY 0.617021 (-5050 5250);
PAINT AQUA (-5050 5250);
FORCEPROP 1 LASTPIN (-4900 5250) $PN 1
J 0
(-4888 5262);
DISPLAY 0.617021 (-4888 5262);
PAINT MONO (-4888 5262);
FORCEPROP 1 LASTPIN (-4700 5250) $PN 2
J 0
(-4738 5262);
DISPLAY 0.617021 (-4738 5262);
PAINT MONO (-4738 5262);
FORCEPROP 1 LAST PATH I78
J 0
(-4850 5400);
DISPLAY 0.978723 (-4850 5400);
PAINT WHITE (-4850 5400);
DISPLAY INVISIBLE (-4850 5400);
FORCEPROP 2 LAST CDS_LIB pure_quanta
J 0
(-4800 5250);
DISPLAY INVISIBLE (-4800 5250);
FORCEPROP 1 LAST LOCATION R2372
J 0
(-4850 5350);
DISPLAY 1.021277 (-4850 5350);
PAINT AQUA (-4850 5350);
DISPLAY INVISIBLE (-4850 5350);
FORCEPROP 0 LAST $SEC 1
J 0
(-4850 5350);
DISPLAY 0.680851 (-4850 5350);
PAINT MONO (-4850 5350);
DISPLAY INVISIBLE (-4850 5350);
FORCEPROP 0 LAST CDS_SEC 1
J 0
(-4850 5350);
DISPLAY 1.021277 (-4850 5350);
DISPLAY INVISIBLE (-4850 5350);
FORCEADD Q_CAP..1
(-4325 4375);
FORCEPROP 1 LAST PART_NUMBER TMP_QCH2336K1B12
J 0
(-4275 4200);
DISPLAY 0.617021 (-4275 4200);
PAINT BLUE (-4275 4200);
DISPLAY INVISIBLE (-4275 4200);
FORCEPROP 1 LAST PACK_TYPE 0402
J 0
(-4275 4250);
DISPLAY 0.617021 (-4275 4250);
PAINT SKYBLUE (-4275 4250);
FORCEPROP 1 LAST VOLTAGE 50V
J 0
(-4275 4400);
DISPLAY 0.617021 (-4275 4400);
PAINT SKYBLUE (-4275 4400);
FORCEPROP 1 LAST TOLERANCE 10%
J 0
(-4275 4350);
DISPLAY 0.617021 (-4275 4350);
PAINT SKYBLUE (-4275 4350);
FORCEPROP 1 LAST MATERIAL X7R
J 0
(-4275 4300);
DISPLAY 0.617021 (-4275 4300);
PAINT SKYBLUE (-4275 4300);
FORCEPROP 1 LAST VALUE 3300PF
J 0
(-4275 4450);
DISPLAY 0.617021 (-4275 4450);
PAINT SKYBLUE (-4275 4450);
FORCEPROP 1 LAST LOCATION PC331
J 0
(-4275 4500);
DISPLAY 0.617021 (-4275 4500);
PAINT AQUA (-4275 4500);
FORCEPROP 1 LASTPIN (-4325 4475) $PN 1
J 0
(-4315 4455);
DISPLAY 0.617021 (-4315 4455);
PAINT MONO (-4315 4455);
FORCEPROP 1 LASTPIN (-4325 4275) $PN 2
J 0
(-4315 4255);
DISPLAY 0.617021 (-4315 4255);
PAINT MONO (-4315 4255);
FORCEPROP 1 LAST PATH I79
J 0
(-4275 4525);
DISPLAY 0.978723 (-4275 4525);
PAINT WHITE (-4275 4525);
DISPLAY INVISIBLE (-4275 4525);
FORCEPROP 2 LAST CDS_LIB pure_quanta
J 0
(-4325 4375);
DISPLAY INVISIBLE (-4325 4375);
FORCEPROP 1 LAST LOCATION PC331
J 0
(-4275 4500);
DISPLAY 1.021277 (-4275 4500);
PAINT AQUA (-4275 4500);
DISPLAY INVISIBLE (-4275 4500);
FORCEPROP 0 LAST $SEC 1
J 0
(-4275 4500);
DISPLAY 0.680851 (-4275 4500);
PAINT MONO (-4275 4500);
DISPLAY INVISIBLE (-4275 4500);
FORCEPROP 0 LAST CDS_SEC 1
J 0
(-4275 4500);
DISPLAY 1.021277 (-4275 4500);
DISPLAY INVISIBLE (-4275 4500);
FORCEADD Q_RES..2
R 2
(-5675 1225);
FORCEPROP 1 LAST PART_NUMBER CS00002JB13
J 2
(-5715 1100);
DISPLAY 0.617021 (-5715 1100);
PAINT BLUE (-5715 1100);
DISPLAY INVISIBLE (-5715 1100);
FORCEPROP 1 LAST PACK_TYPE 0402LF
J 2
(-5715 1050);
DISPLAY 0.617021 (-5715 1050);
PAINT SKYBLUE (-5715 1050);
FORCEPROP 1 LAST VALUE 0
J 2
(-5720 1300);
DISPLAY 0.617021 (-5720 1300);
PAINT SKYBLUE (-5720 1300);
FORCEPROP 1 LAST TOLERANCE 5%
J 2
(-5720 1250);
DISPLAY 0.617021 (-5720 1250);
PAINT SKYBLUE (-5720 1250);
FORCEPROP 1 LAST MATERIAL CHIP
J 2
(-5715 1150);
DISPLAY 0.617021 (-5715 1150);
PAINT SKYBLUE (-5715 1150);
FORCEPROP 1 LAST WATTAGE 1/16W
J 2
(-5715 1200);
DISPLAY 0.617021 (-5715 1200);
PAINT SKYBLUE (-5715 1200);
FORCEPROP 1 LAST LOCATION PR171
J 2
(-5720 1350);
DISPLAY 0.617021 (-5720 1350);
PAINT AQUA (-5720 1350);
FORCEPROP 1 LASTPIN (-5675 1325) $PN 1
J 2
(-5680 1287);
DISPLAY 0.617021 (-5680 1287);
PAINT MONO (-5680 1287);
FORCEPROP 1 LASTPIN (-5675 1125) $PN 2
J 2
(-5680 1135);
DISPLAY 0.617021 (-5680 1135);
PAINT MONO (-5680 1135);
FORCEPROP 1 LAST PATH I8
J 2
(-5725 1400);
DISPLAY 0.978723 (-5725 1400);
PAINT WHITE (-5725 1400);
DISPLAY INVISIBLE (-5725 1400);
FORCEPROP 2 LAST CDS_LIB pure_quanta
J 2
(-5675 1225);
DISPLAY INVISIBLE (-5675 1225);
FORCEPROP 1 LAST LOCATION PR171
J 2
(-5725 1400);
DISPLAY 1.021277 (-5725 1400);
PAINT AQUA (-5725 1400);
DISPLAY INVISIBLE (-5725 1400);
FORCEPROP 0 LAST $SEC 1
J 2
(-5725 1400);
DISPLAY 0.680851 (-5725 1400);
PAINT MONO (-5725 1400);
DISPLAY INVISIBLE (-5725 1400);
FORCEPROP 0 LAST CDS_SEC 1
J 2
(-5725 1400);
DISPLAY 1.021277 (-5725 1400);
DISPLAY INVISIBLE (-5725 1400);
FORCEADD Q_RES..1
(-4800 5400);
FORCEPROP 1 LAST PART_NUMBER CS03322FB03
J 0
(-4675 5450);
DISPLAY 0.617021 (-4675 5450);
PAINT BLUE (-4675 5450);
DISPLAY INVISIBLE (-4675 5450);
FORCEPROP 1 LAST TOLERANCE 1%
J 0
(-4625 5400);
DISPLAY 0.617021 (-4625 5400);
PAINT SKYBLUE (-4625 5400);
FORCEPROP 1 LAST MATERIAL CHIP
J 0
(-4675 5500);
DISPLAY 0.617021 (-4675 5500);
PAINT SKYBLUE (-4675 5500);
FORCEPROP 1 LAST VALUE 33.2
J 2
(-4650 5400);
DISPLAY 0.617021 (-4650 5400);
PAINT SKYBLUE (-4650 5400);
FORCEPROP 1 LAST WATTAGE 1/16W
J 2
(-4350 5500);
DISPLAY 0.617021 (-4350 5500);
PAINT SKYBLUE (-4350 5500);
FORCEPROP 1 LAST PACK_TYPE 0402LF
J 0
(-4550 5400);
DISPLAY 0.617021 (-4550 5400);
PAINT SKYBLUE (-4550 5400);
FORCEPROP 1 LAST LOCATION R2371
J 0
(-5050 5400);
DISPLAY 0.617021 (-5050 5400);
PAINT AQUA (-5050 5400);
FORCEPROP 1 LASTPIN (-4900 5400) $PN 1
J 0
(-4888 5412);
DISPLAY 0.617021 (-4888 5412);
PAINT MONO (-4888 5412);
FORCEPROP 1 LASTPIN (-4700 5400) $PN 2
J 0
(-4738 5412);
DISPLAY 0.617021 (-4738 5412);
PAINT MONO (-4738 5412);
FORCEPROP 1 LAST PATH I80
J 0
(-4850 5550);
DISPLAY 0.978723 (-4850 5550);
PAINT WHITE (-4850 5550);
DISPLAY INVISIBLE (-4850 5550);
FORCEPROP 2 LAST CDS_LIB pure_quanta
J 0
(-4800 5400);
DISPLAY INVISIBLE (-4800 5400);
FORCEPROP 1 LAST LOCATION R2371
J 0
(-4850 5500);
DISPLAY 1.021277 (-4850 5500);
PAINT AQUA (-4850 5500);
DISPLAY INVISIBLE (-4850 5500);
FORCEPROP 0 LAST $SEC 1
J 0
(-4850 5500);
DISPLAY 0.680851 (-4850 5500);
PAINT MONO (-4850 5500);
DISPLAY INVISIBLE (-4850 5500);
FORCEPROP 0 LAST CDS_SEC 1
J 0
(-4850 5500);
DISPLAY 1.021277 (-4850 5500);
DISPLAY INVISIBLE (-4850 5500);
FORCEADD VCC15..1
(-4500 5675);
FORCEPROP 3 LASTPIN (-4500 5625) SIG_NAME P3V3_AUX\g
J 0
(-4490 5635);
DISPLAY 0.659574 (-4490 5635);
PAINT MONO (-4490 5635);
DISPLAY INVISIBLE (-4490 5635);
FORCEPROP 1 LAST HDL_POWER P3V3_AUX
J 1
(-4500 5725);
DISPLAY 0.617021 (-4500 5725);
PAINT GREEN (-4500 5725);
FORCEPROP 1 LAST PATH I81
J 0
(-4450 5700);
DISPLAY 0.872340 (-4450 5700);
PAINT AQUA (-4450 5700);
DISPLAY INVISIBLE (-4450 5700);
FORCEPROP 2 LAST CDS_LIB logical_power
J 0
(-4500 5675);
DISPLAY INVISIBLE (-4500 5675);
FORCEADD Q_CAP..2
(-4300 6275);
FORCEPROP 1 LAST PART_NUMBER TMP_QCH21006JB10
J 1
(-4025 6225);
DISPLAY 0.617021 (-4025 6225);
PAINT BLUE (-4025 6225);
DISPLAY INVISIBLE (-4025 6225);
FORCEPROP 1 LAST MATERIAL X7R
J 0
(-3825 6275);
DISPLAY 0.617021 (-3825 6275);
PAINT SKYBLUE (-3825 6275);
FORCEPROP 1 LAST PACK_TYPE 0402
J 1
(-3750 6175);
DISPLAY 0.617021 (-3750 6175);
PAINT SKYBLUE (-3750 6175);
FORCEPROP 1 LAST VALUE 1000PF
J 2
(-3975 6275);
DISPLAY 0.617021 (-3975 6275);
PAINT SKYBLUE (-3975 6275);
FORCEPROP 1 LAST VOLTAGE 50V
J 0
(-3950 6275);
DISPLAY 0.617021 (-3950 6275);
PAINT SKYBLUE (-3950 6275);
FORCEPROP 1 LAST TOLERANCE 5%
J 2
(-3650 6225);
DISPLAY 0.617021 (-3650 6225);
PAINT SKYBLUE (-3650 6225);
FORCEPROP 1 LAST LOCATION C3267
J 1
(-4475 6275);
DISPLAY 0.617021 (-4475 6275);
PAINT AQUA (-4475 6275);
FORCEPROP 1 LASTPIN (-4400 6275) $PN 1
J 0
(-4410 6290);
DISPLAY 0.617021 (-4410 6290);
PAINT MONO (-4410 6290);
FORCEPROP 1 LASTPIN (-4200 6275) $PN 2
J 0
(-4215 6290);
DISPLAY 0.617021 (-4215 6290);
PAINT MONO (-4215 6290);
FORCEPROP 1 LAST PATH I82
J 0
(-4300 6475);
DISPLAY 0.978723 (-4300 6475);
PAINT WHITE (-4300 6475);
DISPLAY INVISIBLE (-4300 6475);
FORCEPROP 2 LAST CDS_LIB pure_quanta
J 0
(-4300 6275);
DISPLAY INVISIBLE (-4300 6275);
FORCEPROP 1 LAST LOCATION C3267
J 0
(-4350 6375);
DISPLAY 1.021277 (-4350 6375);
PAINT AQUA (-4350 6375);
DISPLAY INVISIBLE (-4350 6375);
FORCEPROP 0 LAST $SEC 1
J 0
(-4350 6375);
DISPLAY 0.680851 (-4350 6375);
PAINT MONO (-4350 6375);
DISPLAY INVISIBLE (-4350 6375);
FORCEPROP 0 LAST CDS_SEC 1
J 0
(-4350 6375);
DISPLAY 1.021277 (-4350 6375);
DISPLAY INVISIBLE (-4350 6375);
FORCEADD UNIVERSAL_GND..1
R 1
(-3575 6275);
FORCEPROP 3 LASTPIN (-3625 6275) SIG_NAME GND\g
J 0
(-3615 6285);
DISPLAY 0.659574 (-3615 6285);
PAINT MONO (-3615 6285);
DISPLAY INVISIBLE (-3615 6285);
FORCEPROP 1 LAST PATH I83
R 1
J 0
(-3575 6350);
DISPLAY 0.872340 (-3575 6350);
PAINT AQUA (-3575 6350);
DISPLAY INVISIBLE (-3575 6350);
FORCEPROP 2 LAST CDS_LIB logical_power
J 0
(-3575 6275);
PAINT MONO (-3575 6275);
DISPLAY INVISIBLE (-3575 6275);
FORCEPROP 1 LAST HDL_POWER GND
R 1
J 1
(-3500 6300);
DISPLAY 0.872340 (-3500 6300);
PAINT GREEN (-3500 6300);
DISPLAY INVISIBLE (-3500 6300);
FORCEADD Q_CAP..2
(-4275 6700);
FORCEPROP 1 LAST PART_NUMBER TMP_QCH21006JB10
J 1
(-4000 6650);
DISPLAY 0.617021 (-4000 6650);
PAINT BLUE (-4000 6650);
DISPLAY INVISIBLE (-4000 6650);
FORCEPROP 1 LAST MATERIAL EMPTY
J 0
(-3800 6700);
DISPLAY 0.617021 (-3800 6700);
PAINT RED (-3800 6700);
FORCEPROP 1 LAST VOLTAGE 50V
J 0
(-3925 6700);
DISPLAY 0.617021 (-3925 6700);
PAINT SKYBLUE (-3925 6700);
FORCEPROP 1 LAST VALUE 1000PF
J 2
(-3950 6700);
DISPLAY 0.617021 (-3950 6700);
PAINT SKYBLUE (-3950 6700);
FORCEPROP 1 LAST TOLERANCE 5%
J 2
(-3625 6650);
DISPLAY 0.617021 (-3625 6650);
PAINT SKYBLUE (-3625 6650);
FORCEPROP 1 LAST PACK_TYPE 0402
J 1
(-3725 6600);
DISPLAY 0.617021 (-3725 6600);
PAINT SKYBLUE (-3725 6600);
FORCEPROP 1 LAST LOCATION C3266
J 1
(-4475 6700);
DISPLAY 0.617021 (-4475 6700);
PAINT AQUA (-4475 6700);
FORCEPROP 1 LASTPIN (-4375 6700) $PN 1
J 0
(-4385 6715);
DISPLAY 0.617021 (-4385 6715);
PAINT MONO (-4385 6715);
FORCEPROP 1 LASTPIN (-4175 6700) $PN 2
J 0
(-4190 6715);
DISPLAY 0.617021 (-4190 6715);
PAINT MONO (-4190 6715);
FORCEPROP 1 LAST PATH I84
J 0
(-4275 6900);
DISPLAY 0.978723 (-4275 6900);
PAINT WHITE (-4275 6900);
DISPLAY INVISIBLE (-4275 6900);
FORCEPROP 2 LAST CDS_LIB pure_quanta
J 0
(-4275 6700);
DISPLAY INVISIBLE (-4275 6700);
FORCEPROP 1 LAST LOCATION C3266
J 0
(-4325 6800);
DISPLAY 1.021277 (-4325 6800);
PAINT AQUA (-4325 6800);
DISPLAY INVISIBLE (-4325 6800);
FORCEPROP 0 LAST $SEC 1
J 0
(-4325 6800);
DISPLAY 0.680851 (-4325 6800);
PAINT MONO (-4325 6800);
DISPLAY INVISIBLE (-4325 6800);
FORCEPROP 0 LAST CDS_SEC 1
J 0
(-4325 6800);
DISPLAY 1.021277 (-4325 6800);
DISPLAY INVISIBLE (-4325 6800);
FORCEADD UNIVERSAL_GND..1
R 1
(-3575 6700);
FORCEPROP 3 LASTPIN (-3625 6700) SIG_NAME GND\g
J 0
(-3615 6710);
DISPLAY 0.659574 (-3615 6710);
PAINT MONO (-3615 6710);
DISPLAY INVISIBLE (-3615 6710);
FORCEPROP 1 LAST PATH I85
R 1
J 0
(-3575 6775);
DISPLAY 0.872340 (-3575 6775);
PAINT AQUA (-3575 6775);
DISPLAY INVISIBLE (-3575 6775);
FORCEPROP 2 LAST CDS_LIB logical_power
J 0
(-3575 6700);
PAINT MONO (-3575 6700);
DISPLAY INVISIBLE (-3575 6700);
FORCEPROP 1 LAST HDL_POWER GND
R 1
J 1
(-3500 6725);
DISPLAY 0.872340 (-3500 6725);
PAINT GREEN (-3500 6725);
DISPLAY INVISIBLE (-3500 6725);
FORCEADD Q_CAP..1
(-1500 5875);
FORCEPROP 1 LAST PART_NUMBER CH6101MEB03
J 0
(-1450 5700);
DISPLAY 0.617021 (-1450 5700);
PAINT BLUE (-1450 5700);
DISPLAY INVISIBLE (-1450 5700);
FORCEPROP 1 LAST TOLERANCE 20%
J 0
(-1450 5850);
DISPLAY 0.617021 (-1450 5850);
PAINT SKYBLUE (-1450 5850);
FORCEPROP 1 LAST MATERIAL X6S
J 0
(-1450 5800);
DISPLAY 0.617021 (-1450 5800);
PAINT SKYBLUE (-1450 5800);
FORCEPROP 1 LAST PACK_TYPE C0402
J 0
(-1450 5750);
DISPLAY 0.617021 (-1450 5750);
PAINT SKYBLUE (-1450 5750);
FORCEPROP 1 LAST VOLTAGE 6.3V
J 0
(-1450 5900);
DISPLAY 0.617021 (-1450 5900);
PAINT SKYBLUE (-1450 5900);
FORCEPROP 1 LAST VALUE 10UF
J 0
(-1450 5950);
DISPLAY 0.617021 (-1450 5950);
PAINT SKYBLUE (-1450 5950);
FORCEPROP 1 LAST LOCATION PC335
J 0
(-1450 6000);
DISPLAY 0.617021 (-1450 6000);
PAINT AQUA (-1450 6000);
FORCEPROP 1 LASTPIN (-1500 5975) $PN 1
J 0
(-1490 5955);
DISPLAY 0.617021 (-1490 5955);
PAINT MONO (-1490 5955);
FORCEPROP 1 LASTPIN (-1500 5775) $PN 2
J 0
(-1490 5755);
DISPLAY 0.617021 (-1490 5755);
PAINT MONO (-1490 5755);
FORCEPROP 1 LAST PATH I86
J 0
(-1450 6025);
DISPLAY 0.978723 (-1450 6025);
PAINT WHITE (-1450 6025);
DISPLAY INVISIBLE (-1450 6025);
FORCEPROP 2 LAST CDS_LIB pure_quanta
J 0
(-1500 5875);
DISPLAY INVISIBLE (-1500 5875);
FORCEPROP 1 LAST LOCATION PC335
J 0
(-1450 6050);
DISPLAY 1.021277 (-1450 6050);
PAINT AQUA (-1450 6050);
DISPLAY INVISIBLE (-1450 6050);
FORCEPROP 0 LAST $SEC 1
J 0
(-1450 6050);
DISPLAY 0.680851 (-1450 6050);
PAINT MONO (-1450 6050);
DISPLAY INVISIBLE (-1450 6050);
FORCEPROP 0 LAST CDS_SEC 1
J 0
(-1450 6050);
DISPLAY 1.021277 (-1450 6050);
DISPLAY INVISIBLE (-1450 6050);
FORCEADD Q_CAP..1
(-1100 5875);
FORCEPROP 1 LAST PART_NUMBER CH5103KEB01
J 0
(-1050 5700);
DISPLAY 0.617021 (-1050 5700);
PAINT BLUE (-1050 5700);
DISPLAY INVISIBLE (-1050 5700);
FORCEPROP 1 LAST VOLTAGE 16V
J 0
(-1050 5900);
DISPLAY 0.617021 (-1050 5900);
PAINT SKYBLUE (-1050 5900);
FORCEPROP 1 LAST TOLERANCE 10%
J 0
(-1050 5850);
DISPLAY 0.617021 (-1050 5850);
PAINT SKYBLUE (-1050 5850);
FORCEPROP 1 LAST MATERIAL X6S
J 0
(-1050 5800);
DISPLAY 0.617021 (-1050 5800);
PAINT SKYBLUE (-1050 5800);
FORCEPROP 1 LAST PACK_TYPE C0402
J 0
(-1050 5750);
DISPLAY 0.617021 (-1050 5750);
PAINT SKYBLUE (-1050 5750);
FORCEPROP 1 LAST VALUE 1UF
J 0
(-1050 5950);
DISPLAY 0.617021 (-1050 5950);
PAINT SKYBLUE (-1050 5950);
FORCEPROP 1 LAST LOCATION PC1173
J 0
(-1050 6000);
DISPLAY 0.617021 (-1050 6000);
PAINT AQUA (-1050 6000);
FORCEPROP 1 LASTPIN (-1100 5975) $PN 1
J 0
(-1090 5955);
DISPLAY 0.617021 (-1090 5955);
FORCEPROP 1 LASTPIN (-1100 5775) $PN 2
J 0
(-1090 5755);
DISPLAY 0.617021 (-1090 5755);
FORCEPROP 1 LAST PATH I87
J 0
(-1050 6025);
DISPLAY 0.978723 (-1050 6025);
PAINT WHITE (-1050 6025);
DISPLAY INVISIBLE (-1050 6025);
FORCEPROP 2 LAST CDS_LIB pure_quanta
J 0
(-1100 5875);
PAINT MONO (-1100 5875);
DISPLAY INVISIBLE (-1100 5875);
FORCEPROP 2 LAST $SEC 1
J 0
(-1050 6075);
DISPLAY 0.680851 (-1050 6075);
PAINT MONO (-1050 6075);
DISPLAY INVISIBLE (-1050 6075);
FORCEPROP 2 LAST CDS_SEC 1
J 0
(-1050 6075);
DISPLAY 1.021277 (-1050 6075);
DISPLAY INVISIBLE (-1050 6075);
FORCEADD Q_CAP..1
(-1450 6350);
FORCEPROP 1 LAST PART_NUMBER CH4104K1B00
J 0
(-1425 6175);
DISPLAY 0.617021 (-1425 6175);
PAINT BLUE (-1425 6175);
DISPLAY INVISIBLE (-1425 6175);
FORCEPROP 1 LAST PACK_TYPE 0402
J 0
(-1400 6225);
DISPLAY 0.617021 (-1400 6225);
PAINT SKYBLUE (-1400 6225);
FORCEPROP 1 LAST MATERIAL EMPTY
J 0
(-1400 6275);
DISPLAY 0.617021 (-1400 6275);
PAINT RED (-1400 6275);
FORCEPROP 1 LAST TOLERANCE 10%
J 0
(-1400 6325);
DISPLAY 0.617021 (-1400 6325);
PAINT SKYBLUE (-1400 6325);
FORCEPROP 1 LAST VOLTAGE 25V
J 0
(-1400 6375);
DISPLAY 0.617021 (-1400 6375);
PAINT SKYBLUE (-1400 6375);
FORCEPROP 1 LAST VALUE 0.1UF
J 0
(-1400 6425);
DISPLAY 0.617021 (-1400 6425);
PAINT SKYBLUE (-1400 6425);
FORCEPROP 1 LAST LOCATION PC334
J 0
(-1400 6475);
DISPLAY 0.617021 (-1400 6475);
PAINT AQUA (-1400 6475);
FORCEPROP 1 LASTPIN (-1450 6450) $PN 1
J 0
(-1440 6430);
DISPLAY 0.617021 (-1440 6430);
PAINT MONO (-1440 6430);
FORCEPROP 1 LASTPIN (-1450 6250) $PN 2
J 0
(-1440 6230);
DISPLAY 0.617021 (-1440 6230);
PAINT MONO (-1440 6230);
FORCEPROP 1 LAST PATH I88
J 0
(-1400 6500);
DISPLAY 0.978723 (-1400 6500);
PAINT WHITE (-1400 6500);
DISPLAY INVISIBLE (-1400 6500);
FORCEPROP 2 LAST CDS_LIB pure_quanta
J 0
(-1450 6350);
DISPLAY INVISIBLE (-1450 6350);
FORCEPROP 1 LAST LOCATION PC334
J 0
(-1400 6525);
DISPLAY 1.021277 (-1400 6525);
PAINT AQUA (-1400 6525);
DISPLAY INVISIBLE (-1400 6525);
FORCEPROP 0 LAST $SEC 1
J 0
(-1400 6525);
DISPLAY 0.680851 (-1400 6525);
PAINT MONO (-1400 6525);
DISPLAY INVISIBLE (-1400 6525);
FORCEPROP 0 LAST CDS_SEC 1
J 0
(-1400 6525);
DISPLAY 1.021277 (-1400 6525);
DISPLAY INVISIBLE (-1400 6525);
FORCEADD Q_CAP..1
(-1100 6350);
FORCEPROP 1 LAST PART_NUMBER CH5103KEB01
J 0
(-1050 6175);
DISPLAY 0.617021 (-1050 6175);
PAINT BLUE (-1050 6175);
DISPLAY INVISIBLE (-1050 6175);
FORCEPROP 1 LAST VOLTAGE 16V
J 0
(-1050 6375);
DISPLAY 0.617021 (-1050 6375);
PAINT SKYBLUE (-1050 6375);
FORCEPROP 1 LAST VALUE 1UF
J 0
(-1050 6425);
DISPLAY 0.617021 (-1050 6425);
PAINT SKYBLUE (-1050 6425);
FORCEPROP 1 LAST PACK_TYPE C0402
J 0
(-1050 6225);
DISPLAY 0.617021 (-1050 6225);
PAINT SKYBLUE (-1050 6225);
FORCEPROP 1 LAST TOLERANCE 10%
J 0
(-1050 6325);
DISPLAY 0.617021 (-1050 6325);
PAINT SKYBLUE (-1050 6325);
FORCEPROP 1 LAST MATERIAL X6S
J 0
(-1050 6275);
DISPLAY 0.617021 (-1050 6275);
PAINT SKYBLUE (-1050 6275);
FORCEPROP 1 LAST LOCATION PC337
J 0
(-1050 6475);
DISPLAY 0.617021 (-1050 6475);
PAINT AQUA (-1050 6475);
FORCEPROP 1 LASTPIN (-1100 6450) $PN 1
J 0
(-1090 6430);
DISPLAY 0.617021 (-1090 6430);
PAINT MONO (-1090 6430);
FORCEPROP 1 LASTPIN (-1100 6250) $PN 2
J 0
(-1090 6230);
DISPLAY 0.617021 (-1090 6230);
PAINT MONO (-1090 6230);
FORCEPROP 1 LAST PATH I89
J 0
(-1050 6500);
DISPLAY 0.978723 (-1050 6500);
PAINT WHITE (-1050 6500);
DISPLAY INVISIBLE (-1050 6500);
FORCEPROP 2 LAST CDS_LIB pure_quanta
J 0
(-1100 6350);
DISPLAY INVISIBLE (-1100 6350);
FORCEPROP 1 LAST LOCATION PC337
J 0
(-1050 6525);
DISPLAY 1.021277 (-1050 6525);
PAINT AQUA (-1050 6525);
DISPLAY INVISIBLE (-1050 6525);
FORCEPROP 0 LAST $SEC 1
J 0
(-1050 6525);
DISPLAY 0.680851 (-1050 6525);
PAINT MONO (-1050 6525);
DISPLAY INVISIBLE (-1050 6525);
FORCEPROP 0 LAST CDS_SEC 1
J 0
(-1050 6525);
DISPLAY 1.021277 (-1050 6525);
DISPLAY INVISIBLE (-1050 6525);
FORCEADD UNIVERSAL_GND..1
(-5675 1000);
FORCEPROP 3 LASTPIN (-5675 1050) SIG_NAME GND\g
J 0
(-5665 1060);
DISPLAY 0.659574 (-5665 1060);
PAINT MONO (-5665 1060);
DISPLAY INVISIBLE (-5665 1060);
FORCEPROP 1 LAST PATH I9
J 0
(-5600 1000);
DISPLAY 0.872340 (-5600 1000);
PAINT AQUA (-5600 1000);
DISPLAY INVISIBLE (-5600 1000);
FORCEPROP 2 LAST CDS_LIB logical_power
J 0
(-5675 1000);
PAINT MONO (-5675 1000);
DISPLAY INVISIBLE (-5675 1000);
FORCEPROP 1 LAST HDL_POWER GND
J 1
(-5650 925);
DISPLAY 0.872340 (-5650 925);
PAINT GREEN (-5650 925);
DISPLAY INVISIBLE (-5650 925);
FORCEADD OFFPAGE..2
(-950 2250);
FORCEPROP 2 LAST $XR0 271 
J 0
(-761 2250);
DISPLAY 0.638298 (-761 2250);
PAINT MONO (-761 2250);
FORCEPROP 2 LAST PATH I90
J 0
(-750 2300);
DISPLAY 1.021277 (-750 2300);
DISPLAY INVISIBLE (-750 2300);
FORCEPROP 2 LAST CDS_LIB standard
J 0
(-950 2250);
DISPLAY INVISIBLE (-950 2250);
FORCEPROP 1 LAST OFFPAGE TRUE
J 0
(-625 2125);
DISPLAY 0.872340 (-625 2125);
PAINT GREEN (-625 2125);
DISPLAY INVISIBLE (-625 2125);
FORCEPROP 1 LAST COMMENT_BODY TRUE
J 0
(-995 2155);
DISPLAY 0.872340 (-995 2155);
PAINT GREEN (-995 2155);
DISPLAY INVISIBLE (-995 2155);
FORCEADD OFFPAGE..4
(-950 2150);
FORCEPROP 2 LAST $XR0 271 
J 0
(-764 2150);
DISPLAY 0.638298 (-764 2150);
PAINT MONO (-764 2150);
FORCEPROP 2 LAST PATH I91
J 0
(-750 2200);
DISPLAY 1.021277 (-750 2200);
DISPLAY INVISIBLE (-750 2200);
FORCEPROP 2 LAST CDS_LIB standard
J 0
(-950 2150);
DISPLAY INVISIBLE (-950 2150);
FORCEPROP 1 LAST OFFPAGE TRUE
J 0
(-625 2025);
DISPLAY 0.872340 (-625 2025);
PAINT GREEN (-625 2025);
DISPLAY INVISIBLE (-625 2025);
FORCEPROP 1 LAST COMMENT_BODY TRUE
J 0
(-975 2050);
DISPLAY 0.872340 (-975 2050);
PAINT GREEN (-975 2050);
DISPLAY INVISIBLE (-975 2050);
FORCEADD OFFPAGE..2
(-950 5550);
FORCEPROP 2 LAST $XR0 267 
J 0
(-761 5550);
DISPLAY 0.638298 (-761 5550);
PAINT MONO (-761 5550);
FORCEPROP 2 LAST PATH I92
J 0
(-750 5600);
DISPLAY 1.021277 (-750 5600);
DISPLAY INVISIBLE (-750 5600);
FORCEPROP 2 LAST CDS_LIB standard
J 0
(-950 5550);
DISPLAY INVISIBLE (-950 5550);
FORCEPROP 1 LAST OFFPAGE TRUE
J 0
(-625 5425);
DISPLAY 0.872340 (-625 5425);
PAINT GREEN (-625 5425);
DISPLAY INVISIBLE (-625 5425);
FORCEPROP 1 LAST COMMENT_BODY TRUE
J 0
(-995 5455);
DISPLAY 0.872340 (-995 5455);
PAINT GREEN (-995 5455);
DISPLAY INVISIBLE (-995 5455);
FORCEADD OFFPAGE..4
(-950 5450);
FORCEPROP 2 LAST $XR0 267 
J 0
(-764 5450);
DISPLAY 0.638298 (-764 5450);
PAINT MONO (-764 5450);
FORCEPROP 2 LAST PATH I93
J 0
(-750 5500);
DISPLAY 1.021277 (-750 5500);
DISPLAY INVISIBLE (-750 5500);
FORCEPROP 2 LAST CDS_LIB standard
J 0
(-950 5450);
DISPLAY INVISIBLE (-950 5450);
FORCEPROP 1 LAST OFFPAGE TRUE
J 0
(-625 5325);
DISPLAY 0.872340 (-625 5325);
PAINT GREEN (-625 5325);
DISPLAY INVISIBLE (-625 5325);
FORCEPROP 1 LAST COMMENT_BODY TRUE
J 0
(-975 5350);
DISPLAY 0.872340 (-975 5350);
PAINT GREEN (-975 5350);
DISPLAY INVISIBLE (-975 5350);
FORCEADD OFFPAGE..2
(-950 5250);
FORCEPROP 2 LAST $XR0 267 
J 0
(-761 5250);
DISPLAY 0.638298 (-761 5250);
PAINT MONO (-761 5250);
FORCEPROP 2 LAST PATH I94
J 0
(-750 5300);
DISPLAY 1.021277 (-750 5300);
DISPLAY INVISIBLE (-750 5300);
FORCEPROP 2 LAST CDS_LIB standard
J 0
(-950 5250);
DISPLAY INVISIBLE (-950 5250);
FORCEPROP 1 LAST OFFPAGE TRUE
J 0
(-625 5125);
DISPLAY 0.872340 (-625 5125);
PAINT GREEN (-625 5125);
DISPLAY INVISIBLE (-625 5125);
FORCEPROP 1 LAST COMMENT_BODY TRUE
J 0
(-995 5155);
DISPLAY 0.872340 (-995 5155);
PAINT GREEN (-995 5155);
DISPLAY INVISIBLE (-995 5155);
FORCEADD OFFPAGE..4
(-950 5150);
FORCEPROP 2 LAST $XR0 267 
J 0
(-764 5150);
DISPLAY 0.638298 (-764 5150);
PAINT MONO (-764 5150);
FORCEPROP 2 LAST PATH I95
J 0
(-750 5200);
DISPLAY 1.021277 (-750 5200);
DISPLAY INVISIBLE (-750 5200);
FORCEPROP 2 LAST CDS_LIB standard
J 0
(-950 5150);
DISPLAY INVISIBLE (-950 5150);
FORCEPROP 1 LAST OFFPAGE TRUE
J 0
(-625 5025);
DISPLAY 0.872340 (-625 5025);
PAINT GREEN (-625 5025);
DISPLAY INVISIBLE (-625 5025);
FORCEPROP 1 LAST COMMENT_BODY TRUE
J 0
(-975 5050);
DISPLAY 0.872340 (-975 5050);
PAINT GREEN (-975 5050);
DISPLAY INVISIBLE (-975 5050);
FORCEADD OFFPAGE..2
(-950 4950);
FORCEPROP 2 LAST $XR0 268 
J 0
(-761 4950);
DISPLAY 0.638298 (-761 4950);
PAINT MONO (-761 4950);
FORCEPROP 2 LAST PATH I96
J 0
(-750 5000);
DISPLAY 1.021277 (-750 5000);
DISPLAY INVISIBLE (-750 5000);
FORCEPROP 2 LAST CDS_LIB standard
J 0
(-950 4950);
DISPLAY INVISIBLE (-950 4950);
FORCEPROP 1 LAST OFFPAGE TRUE
J 0
(-625 4825);
DISPLAY 0.872340 (-625 4825);
PAINT GREEN (-625 4825);
DISPLAY INVISIBLE (-625 4825);
FORCEPROP 1 LAST COMMENT_BODY TRUE
J 0
(-995 4855);
DISPLAY 0.872340 (-995 4855);
PAINT GREEN (-995 4855);
DISPLAY INVISIBLE (-995 4855);
FORCEADD OFFPAGE..4
(-950 4850);
FORCEPROP 2 LAST $XR0 268 
J 0
(-764 4850);
DISPLAY 0.638298 (-764 4850);
PAINT MONO (-764 4850);
FORCEPROP 2 LAST PATH I97
J 0
(-750 4900);
DISPLAY 1.021277 (-750 4900);
DISPLAY INVISIBLE (-750 4900);
FORCEPROP 2 LAST CDS_LIB standard
J 0
(-950 4850);
DISPLAY INVISIBLE (-950 4850);
FORCEPROP 1 LAST OFFPAGE TRUE
J 0
(-625 4725);
DISPLAY 0.872340 (-625 4725);
PAINT GREEN (-625 4725);
DISPLAY INVISIBLE (-625 4725);
FORCEPROP 1 LAST COMMENT_BODY TRUE
J 0
(-975 4750);
DISPLAY 0.872340 (-975 4750);
PAINT GREEN (-975 4750);
DISPLAY INVISIBLE (-975 4750);
FORCEADD OFFPAGE..2
(-950 4650);
FORCEPROP 2 LAST $XR0 268 
J 0
(-761 4650);
DISPLAY 0.638298 (-761 4650);
PAINT MONO (-761 4650);
FORCEPROP 2 LAST PATH I98
J 0
(-750 4700);
DISPLAY 1.021277 (-750 4700);
DISPLAY INVISIBLE (-750 4700);
FORCEPROP 2 LAST CDS_LIB standard
J 0
(-950 4650);
DISPLAY INVISIBLE (-950 4650);
FORCEPROP 1 LAST OFFPAGE TRUE
J 0
(-625 4525);
DISPLAY 0.872340 (-625 4525);
PAINT GREEN (-625 4525);
DISPLAY INVISIBLE (-625 4525);
FORCEPROP 1 LAST COMMENT_BODY TRUE
J 0
(-995 4555);
DISPLAY 0.872340 (-995 4555);
PAINT GREEN (-995 4555);
DISPLAY INVISIBLE (-995 4555);
FORCEADD OFFPAGE..4
(-950 4550);
FORCEPROP 2 LAST $XR0 268 
J 0
(-764 4550);
DISPLAY 0.638298 (-764 4550);
PAINT MONO (-764 4550);
FORCEPROP 2 LAST PATH I99
J 0
(-750 4600);
DISPLAY 1.021277 (-750 4600);
DISPLAY INVISIBLE (-750 4600);
FORCEPROP 2 LAST CDS_LIB standard
J 0
(-950 4550);
DISPLAY INVISIBLE (-950 4550);
FORCEPROP 1 LAST OFFPAGE TRUE
J 0
(-625 4425);
DISPLAY 0.872340 (-625 4425);
PAINT GREEN (-625 4425);
DISPLAY INVISIBLE (-625 4425);
FORCEPROP 1 LAST COMMENT_BODY TRUE
J 0
(-975 4450);
DISPLAY 0.872340 (-975 4450);
PAINT GREEN (-975 4450);
DISPLAY INVISIBLE (-975 4450);
FORCEADD QUANTA_TITLE_BLOCK_C..1
(1725 325);
FORCEPROP 0 LAST CDS_CON_LAST_MODIFIED Fri Aug 25 14:04:36 2023
J 0
(-160 340);
DISPLAY INVISIBLE (-160 340);
FORCEPROP 1 LAST CUSTOM_TXT_CDS <CON_LAST_MODIFIED>
J 0
(-160 340);
DISPLAY 0.978723 (-160 340);
FORCEPROP 2 LAST CUSTOM_TXT_CDS <XR_PAGE_TITLE>
J 0
(-6165 5575);
DISPLAY 0.638298 (-6165 5575);
PAINT PINK (-6165 5575);
DISPLAY INVISIBLE (-6165 5575);
FORCEPROP 1 LAST CUSTOM_TXT_CDS <NAME_2>
J 0
(-1450 375);
FORCEPROP 1 LAST CUSTOM_TXT_CDS <NAME_1>
J 0
(-1450 500);
FORCEPROP 1 LAST CUSTOM_TXT_CDS <Q_NUMBER>
J 0
(322 428);
DISPLAY 1.212766 (322 428);
FORCEPROP 1 LAST CUSTOM_TXT_CDS <Q_PROJ>
J 0
(-657 427);
DISPLAY 1.212766 (-657 427);
FORCEPROP 1 LAST CUSTOM_TXT_CDS <Q_REV>
J 0
(1541 428);
DISPLAY 1.212766 (1541 428);
FORCEPROP 1 LAST CUSTOM_TXT_CDS <CON_PAGE_NUM> OF <CON_TOTAL_PAGES>
J 0
(1279 343);
DISPLAY 0.978723 (1279 343);
FORCEPROP 1 LAST Q_TITLE VCCIN/VCCFA_EHV_FIVRA CPU0 VR(1/7)
J 0
(-7550 375);
DISPLAY 2.446809 (-7550 375);
PAINT GREEN (-7550 375);
FORCEPROP 1 LAST Q_DEPT 
J 1
(-2038 374);
DISPLAY 1.957447 (-2038 374);
PAINT GREEN (-2038 374);
FORCEPROP 2 LAST CDS_XR_PAGE_TITLE CR-266 : @S9S_MB_2U_LIB.S9S_MB_2U(SCH_1):PAGE266
J 0
(-6165 5575);
DISPLAY 0.638298 (-6165 5575);
PAINT PINK (-6165 5575);
DISPLAY INVISIBLE (-6165 5575);
FORCEPROP 2 LAST CDS_LIB pure_quanta
J 0
(1725 325);
DISPLAY INVISIBLE (1725 325);
FORCEPROP 1 LAST CDS_LMAN_SYM_OUTLINE -9475,6775,100,-125
J 0
(1725 325);
DISPLAY 0.468085 (1725 325);
PAINT GREEN (1725 325);
DISPLAY INVISIBLE (1725 325);
FORCEPROP 2 LAST PAGE_BORDER TRUE
J 0
(-6165 5575);
DISPLAY 0.638298 (-6165 5575);
PAINT PINK (-6165 5575);
DISPLAY INVISIBLE (-6165 5575);
FORCEPROP 1 LAST COMMENT_BODY TRUE
J 0
(1737 312);
DISPLAY 0.978723 (1737 312);
PAINT GREEN (1737 312);
DISPLAY INVISIBLE (1737 312);
FORCEADD DNS..1
(775 2675);
PAINT RED (775 2675);
FORCEPROP 2 LAST CDS_LIB mstr_misc
J 0
(775 2675);
DISPLAY INVISIBLE (775 2675);
FORCEPROP 1 LAST COMMENT_BODY TRUE
R 1
J 0
(850 2450);
DISPLAY 0.872340 (850 2450);
PAINT GREEN (850 2450);
DISPLAY INVISIBLE (850 2450);
FORCEADD DNS..1
(975 1900);
PAINT RED (975 1900);
FORCEPROP 2 LAST CDS_LIB mstr_misc
J 0
(975 1900);
PAINT MONO (975 1900);
DISPLAY INVISIBLE (975 1900);
FORCEPROP 1 LAST COMMENT_BODY TRUE
R 1
J 0
(1050 1675);
DISPLAY 0.872340 (1050 1675);
PAINT GREEN (1050 1675);
DISPLAY INVISIBLE (1050 1675);
FORCEADD DNS..1
(575 1400);
PAINT RED (575 1400);
FORCEPROP 2 LAST CDS_LIB mstr_misc
J 0
(575 1400);
DISPLAY INVISIBLE (575 1400);
FORCEPROP 1 LAST COMMENT_BODY TRUE
R 1
J 0
(650 1175);
DISPLAY 0.872340 (650 1175);
PAINT GREEN (650 1175);
DISPLAY INVISIBLE (650 1175);
FORCEADD DNS..1
(-4275 6725);
PAINT RED (-4275 6725);
FORCEPROP 2 LAST CDS_LIB mstr_misc
J 0
(-4275 6725);
DISPLAY INVISIBLE (-4275 6725);
FORCEPROP 1 LAST COMMENT_BODY TRUE
R 1
J 0
(-4200 6500);
DISPLAY 0.872340 (-4200 6500);
PAINT GREEN (-4200 6500);
DISPLAY INVISIBLE (-4200 6500);
FORCEADD DNS..2
(-1700 2975);
PAINT RED (-1700 2975);
FORCEPROP 2 LAST CDS_LIB mstr_misc
J 0
(-1700 2975);
DISPLAY INVISIBLE (-1700 2975);
FORCEPROP 1 LAST COMMENT_BODY TRUE
R 1
J 0
(-1625 2750);
DISPLAY 0.872340 (-1625 2750);
PAINT GREEN (-1625 2750);
DISPLAY INVISIBLE (-1625 2750);
FORCEADD DNS..2
(-1675 2675);
PAINT RED (-1675 2675);
FORCEPROP 2 LAST CDS_LIB mstr_misc
J 0
(-1675 2675);
DISPLAY INVISIBLE (-1675 2675);
FORCEPROP 1 LAST COMMENT_BODY TRUE
R 1
J 0
(-1600 2450);
DISPLAY 0.872340 (-1600 2450);
PAINT GREEN (-1600 2450);
DISPLAY INVISIBLE (-1600 2450);
FORCEADD DNS..1
(-1175 1125);
PAINT RED (-1175 1125);
FORCEPROP 2 LAST CDS_LIB mstr_misc
J 0
(-1175 1125);
DISPLAY INVISIBLE (-1175 1125);
FORCEPROP 1 LAST COMMENT_BODY TRUE
R 1
J 0
(-1100 900);
DISPLAY 0.872340 (-1100 900);
PAINT GREEN (-1100 900);
DISPLAY INVISIBLE (-1100 900);
FORCEADD DNS..2
(-4125 1900);
PAINT RED (-4125 1900);
FORCEPROP 2 LAST CDS_LIB mstr_misc
J 0
(-4125 1900);
DISPLAY INVISIBLE (-4125 1900);
FORCEPROP 1 LAST COMMENT_BODY TRUE
R 1
J 0
(-4050 1675);
DISPLAY 0.872340 (-4050 1675);
PAINT GREEN (-4050 1675);
DISPLAY INVISIBLE (-4050 1675);
FORCEADD DNS..1
(-4000 875);
PAINT RED (-4000 875);
FORCEPROP 2 LAST CDS_LIB mstr_misc
J 0
(-4000 875);
DISPLAY INVISIBLE (-4000 875);
FORCEPROP 1 LAST COMMENT_BODY TRUE
R 1
J 0
(-3925 650);
DISPLAY 0.872340 (-3925 650);
PAINT GREEN (-3925 650);
DISPLAY INVISIBLE (-3925 650);
FORCEADD DNS..1
(-4400 900);
PAINT RED (-4400 900);
FORCEPROP 2 LAST CDS_LIB mstr_misc
J 0
(-4400 900);
DISPLAY INVISIBLE (-4400 900);
FORCEPROP 1 LAST COMMENT_BODY TRUE
R 1
J 0
(-4325 675);
DISPLAY 0.872340 (-4325 675);
PAINT GREEN (-4325 675);
DISPLAY INVISIBLE (-4325 675);
FORCEADD DNS..1
(-5075 5575);
PAINT RED (-5075 5575);
FORCEPROP 2 LAST CDS_LIB mstr_misc
J 0
(-5075 5575);
DISPLAY INVISIBLE (-5075 5575);
FORCEPROP 1 LAST COMMENT_BODY TRUE
R 1
J 0
(-5000 5350);
DISPLAY 0.872340 (-5000 5350);
PAINT GREEN (-5000 5350);
DISPLAY INVISIBLE (-5000 5350);
FORCEADD DNS..2
(-5175 1225);
PAINT RED (-5175 1225);
FORCEPROP 2 LAST CDS_LIB mstr_misc
J 0
(-5175 1225);
DISPLAY INVISIBLE (-5175 1225);
FORCEPROP 1 LAST COMMENT_BODY TRUE
R 1
J 0
(-5100 1000);
DISPLAY 0.872340 (-5100 1000);
PAINT GREEN (-5100 1000);
DISPLAY INVISIBLE (-5100 1000);
FORCEADD DNS..2
(-6025 1450);
PAINT RED (-6025 1450);
FORCEPROP 2 LAST CDS_LIB mstr_misc
J 0
(-6025 1450);
PAINT MONO (-6025 1450);
DISPLAY INVISIBLE (-6025 1450);
FORCEPROP 1 LAST COMMENT_BODY TRUE
R 1
J 0
(-5950 1225);
DISPLAY 0.872340 (-5950 1225);
PAINT GREEN (-5950 1225);
DISPLAY INVISIBLE (-5950 1225);
FORCEADD DNS..1
(-1425 6350);
PAINT RED (-1425 6350);
FORCEPROP 2 LAST CDS_LIB mstr_misc
J 0
(-1425 6350);
DISPLAY INVISIBLE (-1425 6350);
FORCEPROP 1 LAST COMMENT_BODY TRUE
R 1
J 0
(-1350 6125);
DISPLAY 0.872340 (-1350 6125);
PAINT GREEN (-1350 6125);
DISPLAY INVISIBLE (-1350 6125);
FORCEADD DNS..1
(-1800 6350);
PAINT RED (-1800 6350);
FORCEPROP 1 LAST COMMENT_BODY TRUE
R 1
J 0
(-1725 6125);
DISPLAY 0.872340 (-1725 6125);
PAINT GREEN (-1725 6125);
DISPLAY INVISIBLE (-1725 6125);
FORCEPROP 2 LAST CDS_LIB mstr_misc
J 0
(-1800 6350);
DISPLAY INVISIBLE (-1800 6350);
WIRE 16 -1 (-5400 2850)(-5400 2900);
WIRE 16 -1 (-5350 2850)(-5400 2850);
WIRE 16 -1 (-5425 1900)(-5425 1950);
WIRE 16 -1 (-5425 1900)(-5050 1900);
WIRE 16 -1 (-300 6625)(-300 6550);
WIRE 16 -1 (1475 2900)(1475 2850);
WIRE 16 -1 (-4500 5625)(-4500 5600);
WIRE 16 -1 (-5550 6700)(-5550 6750);
WIRE 16 -1 (-5550 6700)(-5225 6700);
WIRE 16 -1 (-5250 4800)(-5250 4700);
WIRE 16 -1 (-5250 3700)(-5250 3600);
WIRE 16 -1 (-5475 1200)(-5475 1275);
WIRE 16 -1 (-5475 1100)(-5475 1200);
WIRE 16 -1 (-5300 1200)(-5475 1200);
WIRE 16 -1 (-6100 2500)(-6100 2450);
WIRE 16 -1 (-700 6150)(-1100 6150);
WIRE 16 -1 (-700 5675)(-1100 5675);
WIRE 16 -1 (750 2425)(750 2450);
WIRE 16 -1 (550 1225)(550 1325);
WIRE 16 -1 (-125 1250)(-125 1350);
WIRE 16 -1 (-4175 6700)(-3625 6700);
WIRE 16 -1 (-4200 6275)(-3625 6275);
WIRE 16 -1 (-1100 2975)(-1100 2950);
WIRE 16 -1 (-1625 2975)(-1100 2975);
WIRE 16 -1 (-1100 2675)(-1100 2650);
WIRE 16 -1 (-1625 2675)(-1100 2675);
WIRE 16 -1 (-1175 950)(-1175 1050);
WIRE 16 -1 (-1800 950)(-1800 1050);
WIRE 16 -1 (-4050 2025)(-3500 2025);
WIRE 16 -1 (-4050 1900)(-3500 1900);
WIRE 16 -1 (-3500 925)(-3500 1000);
WIRE 16 -1 (-3700 700)(-3700 625);
WIRE 16 -1 (-4050 700)(-3700 700);
WIRE 16 -1 (-3700 800)(-3700 700);
WIRE 16 -1 (-4425 700)(-4425 650);
WIRE 16 -1 (-4750 700)(-4425 700);
WIRE 16 -1 (-4425 800)(-4425 700);
WIRE 16 -1 (-6325 5600)(-6125 5600);
WIRE 16 -1 (-5275 4025)(-5275 3975);
WIRE 16 -1 (-5275 4025)(-5700 4025);
WIRE 16 -1 (-5550 2925)(-5550 2875);
WIRE 16 -1 (-5550 2925)(-5925 2925);
WIRE 16 -1 (-5675 1125)(-5675 1050);
WIRE 16 -1 (-2075 5550)(-1000 5550);
FORCEPROP 2 LAST SIG_NAME PVCCIN_CPU0_PWM1
J 0
(-1885 5560);
DISPLAY 0.617021 (-1885 5560);
WIRE 16 -1 (-2075 5150)(-1000 5150);
FORCEPROP 2 LAST SIG_NAME PVCCIN_CPU0_IMON2
J 0
(-1885 5160);
DISPLAY 0.617021 (-1885 5160);
WIRE 16 -1 (-2075 5450)(-1000 5450);
FORCEPROP 2 LAST SIG_NAME PVCCIN_CPU0_IMON1
J 0
(-1885 5460);
DISPLAY 0.617021 (-1885 5460);
WIRE 16 -1 (-2075 6250)(-1925 6250);
WIRE 16 -1 (-1925 6250)(-1925 6075);
WIRE 16 -1 (-1500 6075)(-1925 6075);
FORCEPROP 2 LAST SIG_NAME PVCCIN_CPU0_VREF
J 0
(-1885 6085);
DISPLAY 0.617021 (-1885 6085);
WIRE 16 -1 (-1500 5975)(-1500 6075);
WIRE 16 -1 (-1100 6075)(-1500 6075);
WIRE 16 -1 (-1100 6075)(-800 6075);
WIRE 16 -1 (-1100 5975)(-1100 6075);
WIRE 17 273 (1646 5425)(1646 6975);
WIRE 17 273 (75 6975)(1646 6975);
WIRE 17 273 (75 5425)(1646 5425);
WIRE 17 273 (75 5425)(75 6975);
WIRE 17 273 (75 4275)(1646 4275);
WIRE 17 273 (1646 5375)(1646 4275);
WIRE 17 273 (75 5375)(75 4275);
WIRE 17 273 (75 5375)(1646 5375);
WIRE 16 -1 (-2075 4350)(-1000 4350);
FORCEPROP 0 LAST SIG_NAME PVCCIN_CPU0_PWM5
J 0
(-1885 4360);
DISPLAY 0.617021 (-1885 4360);
WIRE 16 -1 (-2075 4050)(-1000 4050);
FORCEPROP 2 LAST SIG_NAME PVCCIN_CPU0_PWM6
J 0
(-1885 4060);
DISPLAY 0.617021 (-1885 4060);
WIRE 16 -1 (-2075 3950)(-1000 3950);
FORCEPROP 2 LAST SIG_NAME PVCCIN_CPU0_IMON6
J 0
(-1885 3960);
DISPLAY 0.617021 (-1885 3960);
WIRE 16 -1 (-2075 4650)(-1000 4650);
FORCEPROP 2 LAST SIG_NAME PVCCIN_CPU0_PWM4
J 0
(-1885 4660);
DISPLAY 0.617021 (-1885 4660);
WIRE 16 -1 (-2075 4550)(-1000 4550);
FORCEPROP 2 LAST SIG_NAME PVCCIN_CPU0_IMON4
J 0
(-1885 4560);
DISPLAY 0.617021 (-1885 4560);
WIRE 16 -1 (-1975 2675)(-1825 2675);
WIRE 16 -1 (-1975 2750)(-2075 2750);
WIRE 16 -1 (-1975 2750)(-1975 2675);
WIRE 16 -1 (-1000 2750)(-1975 2750);
FORCEPROP 2 LAST SIG_NAME PVCCFA_EHV_FIVRA_CPU0_IMON3
J 0
(-1885 2760);
DISPLAY 0.617021 (-1885 2760);
WIRE 16 -1 (-2075 2850)(-1000 2850);
FORCEPROP 0 LAST SIG_NAME PVCCFA_EHV_FIVRA_CPU0_PWM3
J 0
(-1885 2860);
DISPLAY 0.617021 (-1885 2860);
WIRE 16 -1 (-2075 4950)(-1000 4950);
FORCEPROP 2 LAST SIG_NAME PVCCIN_CPU0_PWM3
J 0
(-1885 4960);
DISPLAY 0.617021 (-1885 4960);
WIRE 16 -1 (-5250 4700)(-5650 4700);
WIRE 16 -1 (-4850 2850)(-5150 2850);
WIRE 16 -1 (-4700 2700)(-4850 2700);
WIRE 16 -1 (-4850 2850)(-4850 2700);
WIRE 16 -1 (-5575 2700)(-4850 2700);
FORCEPROP 2 LAST SIG_NAME IRQ_PVCCIN_CPU0_VRHOT_R_N
J 0
(-5585 2710);
DISPLAY 0.617021 (-5585 2710);
WIRE 16 2175 (-6050 2750)(-4725 2750);
WIRE 16 2175 (-4725 2750)(-4725 2650);
WIRE 16 2175 (-6050 2750)(-6050 2650);
WIRE 16 2175 (-6050 2650)(-4725 2650);
WIRE 16 -1 (-3425 3150)(-3625 3150);
WIRE 16 -1 (-3625 3075)(-3625 3150);
WIRE 16 -1 (-4275 3175)(-4275 3075);
WIRE 16 -1 (-3625 3075)(-4275 3075);
WIRE 16 -1 (-6950 3075)(-6250 3075);
FORCEPROP 2 LAST SIG_NAME VSENSE_PVCCFA_EHV_FIVRA_CPU0_DN
J 0
(-6860 3085);
DISPLAY 0.489362 (-6860 3085);
WIRE 16 -1 (-4275 3075)(-6250 3075);
WIRE 16 -1 (-6250 2925)(-6250 3075);
WIRE 16 -1 (-6250 2925)(-6125 2925);
WIRE 16 -1 (-4500 5550)(-5025 5550);
WIRE 16 -1 (-4500 5600)(-5025 5600);
WIRE 16 -1 (-4500 5600)(-4500 5550);
WIRE 16 -1 (-3500 1000)(-3425 1000);
WIRE 16 -1 (-4050 800)(-4050 700);
WIRE 16 -1 (-4750 800)(-4750 700);
WIRE 16 -1 (-5250 3600)(-5650 3600);
WIRE 16 -1 (-6100 2450)(-5800 2450);
WIRE 16 -1 (-5350 2450)(-5800 2450);
WIRE 16 -1 (-5800 2550)(-5800 2450);
WIRE 16 -1 (-5350 2550)(-5800 2550);
WIRE 16 -1 (-300 6550)(-675 6550);
WIRE 16 -1 (-1100 6250)(-1100 6150);
WIRE 16 -1 (-1450 6250)(-1450 6150);
WIRE 16 -1 (-1100 6150)(-1450 6150);
WIRE 16 -1 (-1825 6150)(-1450 6150);
WIRE 16 -1 (-1825 6250)(-1825 6150);
WIRE 16 -1 (-1100 5675)(-1100 5775);
WIRE 16 -1 (-1500 5675)(-1100 5675);
WIRE 16 -1 (-1500 5775)(-1500 5675);
WIRE 16 -1 (1475 1900)(1050 1900);
WIRE 16 -1 (750 2775)(750 2850);
WIRE 16 -1 (1075 2850)(750 2850);
WIRE 16 -1 (1075 2750)(1075 2850);
WIRE 16 -1 (1475 2050)(1475 1900);
WIRE 16 -1 (1475 2050)(1050 2050);
WIRE 16 -1 (1475 2200)(1050 2200);
WIRE 16 -1 (1475 2200)(1475 2050);
WIRE 16 -1 (1475 2850)(1075 2850);
WIRE 16 -1 (1475 2850)(1475 2200);
WIRE 16 -1 (750 2575)(750 2450);
WIRE 16 -1 (750 2450)(1075 2450);
WIRE 16 -1 (1075 2550)(1075 2450);
WIRE 16 -1 (-5475 1100)(-5300 1100);
WIRE 16 -1 (-5150 2550)(-3425 2550);
FORCEPROP 2 LAST SIG_NAME PVCCIN_CPU0_VR_FAULT
J 0
(-4385 2560);
DISPLAY 0.617021 (-4385 2560);
WIRE 16 -1 (-6100 2150)(-5050 2150);
FORCEPROP 2 LAST SIG_NAME FM_PVCCFA_EHV_FIVRA_CPU0_EN
J 0
(-6035 2160);
DISPLAY 0.617021 (-6035 2160);
WIRE 16 -1 (-4475 2450)(-5150 2450);
WIRE 16 -1 (-5575 2300)(-4475 2300);
WIRE 16 -1 (-4475 2300)(-4475 2450);
WIRE 16 -1 (-4475 2300)(-3425 2300);
FORCEPROP 2 LAST SIG_NAME PVCCIN_CPU0_PIN_ALERT
J 0
(-4385 2310);
DISPLAY 0.617021 (-4385 2310);
WIRE 16 -1 (-3425 2700)(-4500 2700);
FORCEPROP 2 LAST SIG_NAME IRQ_PVCCIN_CPU0_VRHOT_N
J 0
(-4185 2710);
DISPLAY 0.489362 (-4185 2710);
WIRE 16 -1 (-6725 2300)(-5775 2300);
FORCEPROP 2 LAST SIG_NAME IRQ_PSYS_CRIT_N
J 0
(-6585 2310);
DISPLAY 0.617021 (-6585 2310);
WIRE 16 -1 (-6050 4025)(-5900 4025);
WIRE 16 -1 (-6050 4025)(-6050 4175);
WIRE 16 -1 (-6950 4175)(-6050 4175);
FORCEPROP 2 LAST SIG_NAME VSENSE_PVCCIN_CPU0_DN
J 0
(-6860 4185);
DISPLAY 0.617021 (-6860 4185);
WIRE 16 -1 (-6050 4175)(-4325 4175);
WIRE 16 -1 (-4325 4275)(-4325 4175);
WIRE 16 -1 (-3625 4175)(-4325 4175);
WIRE 16 -1 (-3625 4175)(-3625 4250);
WIRE 16 -1 (-3425 4250)(-3625 4250);
WIRE 16 -1 (-3625 4500)(-3425 4500);
WIRE 16 -1 (-3625 4550)(-3625 4500);
WIRE 16 -1 (-4325 4475)(-4325 4550);
WIRE 16 -1 (-3625 4550)(-4325 4550);
FORCEPROP 2 LAST SIG_NAME SH_PVCCIN_CPU0_R
J 0
(-4235 4560);
DISPLAY 0.617021 (-4235 4560);
WIRE 16 -1 (-4675 4550)(-4325 4550);
WIRE 16 -1 (-4400 5100)(-3425 5100);
FORCEPROP 2 LAST SIG_NAME NC_PVCCIN_CPU0_SMB_ALERT
J 0
(-4310 5110);
DISPLAY 0.617021 (-4310 5110);
WIRE 16 -1 (-3425 5250)(-4700 5250);
FORCEPROP 2 LAST SIG_NAME SMB_DIO_PVCCIN_CPU0
J 0
(-4310 5260);
DISPLAY 0.617021 (-4310 5260);
WIRE 16 -1 (-3425 5400)(-4700 5400);
FORCEPROP 2 LAST SIG_NAME SMB_CLK_PVCCIN_CPU0
J 0
(-4310 5410);
DISPLAY 0.617021 (-4310 5410);
WIRE 16 -1 (-2075 6550)(-1825 6550);
FORCEPROP 2 LAST SIG_NAME PVCCIN_CPU0_VCC
J 0
(-1885 6560);
DISPLAY 0.617021 (-1885 6560);
WIRE 16 -1 (-1825 6450)(-1825 6550);
WIRE 16 -1 (-1825 6550)(-1450 6550);
WIRE 16 -1 (-1450 6450)(-1450 6550);
WIRE 16 -1 (-1100 6550)(-1450 6550);
WIRE 16 -1 (-875 6550)(-1100 6550);
WIRE 16 -1 (-1100 6450)(-1100 6550);
WIRE 16 -1 (-2075 5250)(-1000 5250);
FORCEPROP 2 LAST SIG_NAME PVCCIN_CPU0_PWM2
J 0
(-1885 5260);
DISPLAY 0.617021 (-1885 5260);
WIRE 16 -1 (-2075 3750)(-1000 3750);
FORCEPROP 2 LAST SIG_NAME PVCCIN_CPU0_PWM7
J 0
(-1885 3760);
DISPLAY 0.617021 (-1885 3760);
WIRE 16 -1 (-2075 3650)(-1000 3650);
FORCEPROP 2 LAST SIG_NAME PVCCIN_CPU0_IMON7
J 0
(-1885 3660);
DISPLAY 0.617021 (-1885 3660);
WIRE 16 -1 (-2075 3450)(-1000 3450);
FORCEPROP 2 LAST SIG_NAME PVCCIN_CPU0_PWM8
J 0
(-1885 3460);
DISPLAY 0.617021 (-1885 3460);
WIRE 16 -1 (-2075 3350)(-1000 3350);
FORCEPROP 2 LAST SIG_NAME PVCCIN_CPU0_IMON8
J 0
(-1885 3360);
DISPLAY 0.617021 (-1885 3360);
WIRE 16 -1 (-2075 3150)(-1000 3150);
FORCEPROP 2 LAST SIG_NAME PVCCFA_EHV_FIVRA_CPU0_PWM4
J 0
(-1885 3160);
DISPLAY 0.617021 (-1885 3160);
WIRE 16 -1 (-1975 3050)(-2075 3050);
WIRE 16 -1 (-1000 3050)(-1975 3050);
FORCEPROP 2 LAST SIG_NAME PVCCFA_EHV_FIVRA_CPU0_IMON4
J 0
(-1885 3060);
DISPLAY 0.617021 (-1885 3060);
WIRE 16 -1 (-1975 3050)(-1975 2975);
WIRE 16 -1 (-1975 2975)(-1825 2975);
WIRE 16 -1 (125 2050)(850 2050);
FORCEPROP 0 LAST CDS_PHYS_NET_NAME SVID_CLK0_CPU0_R
J 0
(165 2098);
PAINT MONO (165 2098);
DISPLAY INVISIBLE (165 2098);
FORCEPROP 2 LAST SIG_NAME SVID_CLK0_CPU0_R
J 0
(190 2060);
DISPLAY 0.489362 (190 2060);
WIRE 16 -1 (125 1900)(850 1900);
FORCEPROP 0 LAST CDS_PHYS_NET_NAME SVID_ALERT0_CPU0_R_N
J 0
(540 1948);
PAINT MONO (540 1948);
DISPLAY INVISIBLE (540 1948);
FORCEPROP 2 LAST SIG_NAME SVID_ALERT0_CPU0_R_N
J 0
(190 1910);
DISPLAY 0.489362 (190 1910);
WIRE 16 -1 (125 2200)(850 2200);
FORCEPROP 0 LAST CDS_PHYS_NET_NAME SVID_DIO0_CPU0_R
J 0
(440 2248);
PAINT MONO (440 2248);
DISPLAY INVISIBLE (440 2248);
FORCEPROP 2 LAST SIG_NAME SVID_DIO0_CPU0_R
J 0
(190 2210);
DISPLAY 0.489362 (190 2210);
WIRE 16 -1 (-125 1650)(-2075 1650);
WIRE 16 -1 (-125 1650)(-125 1550);
WIRE 16 -1 (-125 1650)(550 1650);
FORCEPROP 2 LAST SIG_NAME PVCCFA_EHV_FIVRA_CPU0_BTSEN
J 0
(-1885 1660);
DISPLAY 0.617021 (-1885 1660);
WIRE 16 -1 (925 1650)(550 1650);
WIRE 16 -1 (550 1525)(550 1650);
WIRE 16 -1 (-2075 2550)(-1000 2550);
FORCEPROP 2 LAST SIG_NAME PVCCFA_EHV_FIVRA_CPU0_PWM2
J 0
(-1885 2560);
DISPLAY 0.617021 (-1885 2560);
WIRE 16 -1 (-1000 2450)(-2075 2450);
FORCEPROP 2 LAST SIG_NAME PVCCFA_EHV_FIVRA_CPU0_IMON2
J 0
(-1885 2460);
DISPLAY 0.617021 (-1885 2460);
WIRE 16 -1 (-2075 2250)(-1000 2250);
FORCEPROP 2 LAST SIG_NAME PVCCFA_EHV_FIVRA_CPU0_PWM1
J 0
(-1885 2260);
DISPLAY 0.617021 (-1885 2260);
WIRE 16 -1 (-1000 2150)(-2075 2150);
FORCEPROP 2 LAST SIG_NAME PVCCFA_EHV_FIVRA_CPU0_IMON1
J 0
(-1885 2160);
DISPLAY 0.617021 (-1885 2160);
WIRE 16 -1 (-2075 4250)(-1000 4250);
FORCEPROP 2 LAST SIG_NAME PVCCIN_CPU0_IMON5
J 0
(-1885 4260);
DISPLAY 0.617021 (-1885 4260);
WIRE 16 -1 (-2075 4850)(-1000 4850);
FORCEPROP 2 LAST SIG_NAME PVCCIN_CPU0_IMON3
J 0
(-1885 4860);
DISPLAY 0.617021 (-1885 4860);
WIRE 16 -1 (-4600 6550)(-5025 6550);
WIRE 16 -1 (-4600 6550)(-3425 6550);
FORCEPROP 2 LAST SIG_NAME PWRGD_PVCCIN_CPU0_R
J 0
(-4460 6560);
DISPLAY 0.617021 (-4460 6560);
WIRE 16 -1 (-4600 6700)(-5025 6700);
WIRE 16 -1 (-4600 6550)(-4600 6700);
WIRE 16 -1 (-4375 6700)(-4600 6700);
WIRE 16 -1 (-5025 6400)(-4600 6400);
WIRE 16 -1 (-4600 6400)(-3425 6400);
FORCEPROP 2 LAST SIG_NAME PVCCIN_CPU0_EN_R
J 0
(-4460 6410);
DISPLAY 0.617021 (-4460 6410);
WIRE 16 -1 (-4600 6400)(-4600 6275);
WIRE 16 -1 (-4400 6275)(-4600 6275);
WIRE 16 -1 (-5025 5950)(-3425 5950);
FORCEPROP 2 LAST SIG_NAME SVID_DIO_PVCCIN_CPU0_R
J 0
(-4460 5960);
DISPLAY 0.617021 (-4460 5960);
WIRE 16 -1 (-3425 6100)(-5025 6100);
FORCEPROP 2 LAST SIG_NAME SVID_CLK_PVCCIN_CPU0_R
J 0
(-4460 6110);
DISPLAY 0.617021 (-4460 6110);
WIRE 16 -1 (-3425 5800)(-5025 5800);
FORCEPROP 2 LAST SIG_NAME SVID_ALERT_PVCCIN_CPU0_R
J 0
(-4460 5810);
DISPLAY 0.617021 (-4460 5810);
WIRE 16 -1 (-1800 1350)(-2075 1350);
WIRE 16 -1 (-1800 1350)(-1800 1250);
WIRE 16 -1 (-1800 1350)(-1175 1350);
FORCEPROP 2 LAST SIG_NAME PVCCIN_CPU0_ATSEN
J 0
(-1885 1360);
DISPLAY 0.617021 (-1885 1360);
WIRE 16 -1 (-950 1350)(-1175 1350);
WIRE 16 -1 (-1175 1250)(-1175 1350);
WIRE 16 -1 (-3625 3400)(-3425 3400);
WIRE 16 -1 (-3625 3450)(-3625 3400);
WIRE 16 -1 (-4275 3375)(-4275 3450);
WIRE 16 -1 (-3625 3450)(-4275 3450);
FORCEPROP 2 LAST SIG_NAME SH_PVCCFA_EHV_FIVRA_CPU0_R
J 0
(-4235 3460);
DISPLAY 0.489362 (-4235 3460);
WIRE 16 -1 (-4625 3450)(-4275 3450);
WIRE 16 -1 (-5100 1100)(-4050 1100);
FORCEPROP 2 LAST SIG_NAME PVCCIN_CPU0_VIN_CSNIN
J 0
(-4385 1110);
DISPLAY 0.617021 (-4385 1110);
WIRE 16 -1 (-4050 1000)(-4050 1100);
WIRE 16 -1 (-3700 1100)(-4050 1100);
WIRE 16 -1 (-3425 1100)(-3700 1100);
WIRE 16 -1 (-3700 1000)(-3700 1100);
WIRE 16 -1 (-4475 2025)(-4250 2025);
WIRE 16 -1 (-4475 2150)(-4475 2025);
WIRE 16 -1 (-4850 2150)(-4475 2150);
WIRE 16 -1 (-4475 2150)(-3425 2150);
FORCEPROP 2 LAST SIG_NAME PVCCFA_EHV_FIVRA_CPU0_EN_R
J 0
(-4385 2160);
DISPLAY 0.617021 (-4385 2160);
WIRE 16 -1 (-4850 1750)(-4475 1750);
WIRE 16 -1 (-4475 1750)(-3425 1750);
FORCEPROP 2 LAST SIG_NAME PWRGD_PVCCFA_EHV_FIVRA_CPU0_R
J 0
(-4385 1760);
DISPLAY 0.617021 (-4385 1760);
WIRE 16 -1 (-4475 1900)(-4850 1900);
WIRE 16 -1 (-4475 1900)(-4475 1750);
WIRE 16 -1 (-4250 1900)(-4475 1900);
WIRE 16 -1 (-4425 1000)(-4425 1200);
WIRE 16 -1 (-4425 1200)(-3425 1200);
FORCEPROP 2 LAST SIG_NAME PVCCIN_CPU0_CSPIN
J 0
(-4385 1210);
DISPLAY 0.617021 (-4385 1210);
WIRE 16 -1 (-5100 1200)(-4750 1200);
WIRE 16 -1 (-4425 1200)(-4750 1200);
WIRE 16 -1 (-4750 1000)(-4750 1200);
WIRE 16 -1 (-5700 3450)(-4825 3450);
FORCEPROP 2 LAST SIG_NAME SH_PVCCFA_EHV_FIVRA_CPU0
J 0
(-5585 3460);
DISPLAY 0.489362 (-5585 3460);
WIRE 16 -1 (-5700 4550)(-4875 4550);
FORCEPROP 2 LAST SIG_NAME SH_PVCCIN_CPU0
J 0
(-5535 4560);
DISPLAY 0.617021 (-5535 4560);
WIRE 16 -1 (-5050 1750)(-6100 1750);
FORCEPROP 2 LAST SIG_NAME PWRGD_PVCCFA_EHV_FIVRA_CPU0
J 0
(-6035 1760);
DISPLAY 0.617021 (-6035 1760);
WIRE 16 -1 (-6200 6550)(-5225 6550);
FORCEPROP 2 LAST SIG_NAME PWRGD_PVCCIN_CPU0
J 0
(-6110 6560);
DISPLAY 0.617021 (-6110 6560);
WIRE 16 -1 (-6200 6400)(-5225 6400);
FORCEPROP 2 LAST SIG_NAME FM_PVCCIN_CPU0_EN
J 0
(-6110 6410);
DISPLAY 0.617021 (-6110 6410);
WIRE 16 -1 (-5400 5250)(-6600 5250);
FORCEPROP 2 LAST SIG_NAME SMB_VR_3V3AUX_SDA_R3
J 0
(-6535 5260);
DISPLAY 0.617021 (-6535 5260);
WIRE 16 -1 (-4900 5250)(-5400 5250);
WIRE 16 -1 (-5400 5650)(-6325 5650);
WIRE 16 -1 (-5400 5250)(-5400 5600);
WIRE 16 -1 (-5225 5600)(-5400 5600);
WIRE 16 -1 (-5400 5600)(-5400 5650);
WIRE 16 -1 (-6950 4550)(-6050 4550);
FORCEPROP 2 LAST SIG_NAME VSENSE_PVCCIN_CPU0_DP
J 0
(-6860 4560);
DISPLAY 0.617021 (-6860 4560);
WIRE 16 -1 (-5950 4550)(-6050 4550);
WIRE 16 -1 (-6050 4700)(-6050 4550);
WIRE 16 -1 (-6050 4700)(-5850 4700);
WIRE 16 -1 (-6200 5800)(-5225 5800);
FORCEPROP 2 LAST SIG_NAME SVID_ALERT0_CPU0_R_N
J 0
(-6110 5810);
DISPLAY 0.617021 (-6110 5810);
WIRE 16 -1 (-5225 5950)(-6200 5950);
FORCEPROP 2 LAST SIG_NAME SVID_DIO0_CPU0_R
J 0
(-6110 5960);
DISPLAY 0.617021 (-6110 5960);
WIRE 16 -1 (-6200 6100)(-5225 6100);
FORCEPROP 2 LAST SIG_NAME SVID_CLK0_CPU0_R
J 0
(-6110 6110);
DISPLAY 0.617021 (-6110 6110);
WIRE 16 -1 (-6600 5400)(-5500 5400);
FORCEPROP 2 LAST SIG_NAME SMB_VR_3V3AUX_SCL_R3
J 0
(-6535 5410);
DISPLAY 0.617021 (-6535 5410);
WIRE 16 -1 (-4900 5400)(-5500 5400);
WIRE 16 -1 (-5500 5550)(-6325 5550);
WIRE 16 -1 (-5500 5400)(-5500 5550);
WIRE 16 -1 (-5225 5550)(-5500 5550);
WIRE 17 273 (-7200 4100)(-6850 4100);
WIRE 17 273 (-6850 4650)(-6850 4100);
WIRE 17 273 (-7200 4100)(-7200 4650);
WIRE 17 273 (-7200 4650)(-6850 4650);
WIRE 16 -1 (-6950 3450)(-6025 3450);
FORCEPROP 2 LAST SIG_NAME VSENSE_PVCCFA_EHV_FIVRA_CPU0_DP
J 0
(-6860 3460);
DISPLAY 0.489362 (-6860 3460);
WIRE 16 -1 (-5950 3450)(-6025 3450);
WIRE 16 -1 (-6025 3450)(-6025 3600);
WIRE 16 -1 (-6025 3600)(-5850 3600);
WIRE 16 -1 (-5675 1325)(-5675 1450);
WIRE 16 -1 (-5675 1450)(-3425 1450);
FORCEPROP 2 LAST SIG_NAME PVCCIN_CPU0_ADDR
J 0
(-4385 1460);
DISPLAY 0.617021 (-4385 1460);
WIRE 16 -1 (-5950 1450)(-5675 1450);
WIRE 16 -1 (-7000 1450)(-6150 1450);
FORCEPROP 2 LAST SIG_NAME PVCCIN_CPU0_VREF
J 0
(-6960 1460);
DISPLAY 0.617021 (-6960 1460);
WIRE 17 273 (-7500 775)(-5925 775);
WIRE 17 273 (-5925 775)(-5925 550);
WIRE 17 273 (-7500 775)(-7500 550);
WIRE 17 273 (-7500 550)(-5925 550);
WIRE 17 273 (-7225 3000)(-6900 3000);
WIRE 17 273 (-6900 3550)(-6900 3000);
WIRE 17 273 (-7225 3000)(-7225 3550);
WIRE 17 273 (-7225 3550)(-6900 3550);
DOT 1 (-5475 1200);
DOT 1 (-5675 1450);
DOT 1 (-6250 3075);
DOT 1 (-5800 2450);
DOT 1 (-6025 3450);
DOT 1 (-6050 4175);
DOT 1 (-6050 4550);
DOT 1 (-5400 5250);
DOT 1 (-5500 5400);
DOT 1 (-5500 5550);
DOT 1 (-5400 5600);
DOT 1 (-4425 700);
DOT 1 (-4750 1200);
DOT 1 (-4425 1200);
DOT 1 (-4475 1900);
DOT 1 (-4475 1750);
DOT 1 (-4475 2150);
DOT 1 (-3700 700);
DOT 1 (-4050 1100);
DOT 1 (-3700 1100);
DOT 1 (-4475 2300);
DOT 1 (-4275 3075);
DOT 1 (-4275 3450);
DOT 1 (-4325 4175);
DOT 1 (-1800 1350);
DOT 1 (-1175 1350);
DOT 1 (-1975 2750);
DOT 1 (-1975 3050);
DOT 1 (-4325 4550);
DOT 1 (-4500 5600);
DOT 1 (-4600 6400);
DOT 1 (-4600 6550);
DOT 1 (-4600 6700);
DOT 1 (-1500 6075);
DOT 1 (-1100 6075);
DOT 1 (-1100 6150);
DOT 1 (-1100 6550);
DOT 1 (-125 1650);
DOT 1 (550 1650);
DOT 1 (750 2450);
DOT 1 (1475 2200);
DOT 1 (1475 2050);
DOT 1 (1075 2850);
DOT 1 (1475 2850);
DOT 1 (-1100 5675);
DOT 1 (-1450 6150);
DOT 1 (-1450 6550);
DOT 1 (-1825 6550);
DOT 1 (-4850 2700);
FORCENOTE
SETVID RATE=25MV/US (FAST)
(100 5525) 0;
DISPLAY LEFT (100 5525);
DISPLAY 0.936170 (100 5525);
PAINT WHITE (100 5525);
FORCENOTE
PDG REV 1.6 FOR 350W SPR+HBM
(100 5450) 0;
DISPLAY LEFT (100 5450);
DISPLAY 0.936170 (100 5450);
PAINT RED (100 5450);
FORCENOTE
PVCCFA_EHV_FIVRA_CPU0 SPECIFICATION
(125 5300) 0;
DISPLAY LEFT (125 5300);
DISPLAY 0.808511 (125 5300);
PAINT WHITE (125 5300);
FORCENOTE
VBOOT=1.8V
(125 5192) 0;
DISPLAY LEFT (125 5192);
DISPLAY 0.936170 (125 5192);
PAINT WHITE (125 5192);
FORCENOTE
VID=1.6V~1.88V(TYP=1.8V)
(125 5117) 0;
DISPLAY LEFT (125 5117);
DISPLAY 0.936170 (125 5117);
PAINT WHITE (125 5117);
FORCENOTE
PVCCIN_CPU0 SPECIFICATION
(100 6872) 0;
DISPLAY LEFT (100 6872);
DISPLAY 1.170213 (100 6872);
PAINT WHITE (100 6872);
FORCENOTE
VBOOT=1.8V
(100 6772) 0;
DISPLAY LEFT (100 6772);
DISPLAY 0.936170 (100 6772);
PAINT WHITE (100 6772);
FORCENOTE
VID=1.6V~1.88V(TYP=1.8 OR1.83V)
(100 6697) 0;
DISPLAY LEFT (100 6697);
DISPLAY 0.936170 (100 6697);
PAINT WHITE (100 6697);
FORCENOTE
RIPPLE=+/-10MV
(100 6622) 0;
DISPLAY LEFT (100 6622);
DISPLAY 0.936170 (100 6622);
PAINT WHITE (100 6622);
FORCENOTE
DC=+/-0.5%
(100 6547) 0;
DISPLAY LEFT (100 6547);
DISPLAY 0.936170 (100 6547);
PAINT WHITE (100 6547);
FORCENOTE
TOTAL TOLERANCE BAND=+/-22MV
(100 6471) 0;
DISPLAY LEFT (100 6471);
DISPLAY 0.936170 (100 6471);
PAINT WHITE (100 6471);
FORCENOTE
ICCIN_MAX.APP=430A
(100 6335) 0;
DISPLAY LEFT (100 6335);
DISPLAY 0.936170 (100 6335);
PAINT RED (100 6335);
FORCENOTE
CURRENT STEP=370A(OVERSHOOT)
(100 6175) 0;
DISPLAY LEFT (100 6175);
DISPLAY 0.936170 (100 6175);
PAINT RED (100 6175);
FORCENOTE
LOAD-LINE=0.5 MOHM
(100 5850) 0;
DISPLAY LEFT (100 5850);
DISPLAY 0.936170 (100 5850);
PAINT WHITE (100 5850);
FORCENOTE
SVID ADDRESS=03H BUS#0
(125 4525) 0;
DISPLAY LEFT (125 4525);
DISPLAY 0.936170 (125 4525);
PAINT WHITE (125 4525);
FORCENOTE
PROTOCOL ID=04H (VR13 10MV VID)
(125 4450) 0;
DISPLAY LEFT (125 4450);
DISPLAY 0.936170 (125 4450);
PAINT WHITE (125 4450);
FORCENOTE
SETVID RATE=10MV/US (FAST)
(125 4375) 0;
DISPLAY LEFT (125 4375);
DISPLAY 0.936170 (125 4375);
PAINT WHITE (125 4375);
FORCENOTE
MAX CURRENT=136A
(125 4825) 0;
DISPLAY LEFT (125 4825);
DISPLAY 0.936170 (125 4825);
PAINT WHITE (125 4825);
FORCENOTE
TDC=102A
(125 4900) 0;
DISPLAY LEFT (125 4900);
DISPLAY 0.936170 (125 4900);
PAINT WHITE (125 4900);
FORCENOTE
DC=+/-0.5% OF VID
(125 4970) 0;
DISPLAY LEFT (125 4970);
DISPLAY 0.936170 (125 4970);
PAINT WHITE (125 4970);
FORCENOTE
RIPPLE=+/-9MV
(125 5042) 0;
DISPLAY LEFT (125 5042);
DISPLAY 0.936170 (125 5042);
PAINT WHITE (125 5042);
FORCENOTE
SLEW RATE=960A/US(OVERSHOOT)
(95 6013) 0;
DISPLAY LEFT (95 6013);
DISPLAY 0.936170 (95 6013);
PAINT WHITE (95 6013);
FORCENOTE
WORK FREQUENCY=700KHZ
(100 5775) 0;
DISPLAY LEFT (100 5775);
DISPLAY 0.936170 (100 5775);
PAINT WHITE (100 5775);
FORCENOTE
SVID ADDRESS=00H BUS#0
(100 5700) 0;
DISPLAY LEFT (100 5700);
DISPLAY 0.936170 (100 5700);
PAINT WHITE (100 5700);
FORCENOTE
PROTOCOL ID=0AH (VR14 10MV VID)
(95 5613) 0;
DISPLAY LEFT (95 5613);
DISPLAY 0.936170 (95 5613);
PAINT WHITE (95 5613);
FORCENOTE
OCP=164A
(125 4750) 0;
DISPLAY LEFT (125 4750);
DISPLAY 0.936170 (125 4750);
PAINT WHITE (125 4750);
FORCENOTE
LOAD-LINE=0.7 MOHM
(125 4675) 0;
DISPLAY LEFT (125 4675);
DISPLAY 0.936170 (125 4675);
PAINT WHITE (125 4675);
FORCENOTE
20220808 UPDATE PDG REV 1.6
(-300 4175) 0;
DISPLAY LEFT (-300 4175);
DISPLAY 1.595745 (-300 4175);
FORCENOTE
PDG REV.1.6 FOR SPR+HBM
(125 4300) 0;
DISPLAY LEFT (125 4300);
DISPLAY 0.936170 (125 4300);
PAINT RED (125 4300);
FORCENOTE
WORK FREQUENCY=700KHZ
(125 4600) 0;
DISPLAY LEFT (125 4600);
DISPLAY 0.936170 (125 4600);
PAINT WHITE (125 4600);
FORCENOTE
TRANSIENT OCP=600A
(525 6250) 0;
DISPLAY LEFT (525 6250);
DISPLAY 0.936170 (525 6250);
PAINT WHITE (525 6250);
FORCENOTE
1081A(UNDERSHOOT)
(100 5925) 0;
DISPLAY LEFT (100 5925);
DISPLAY 0.936170 (100 5925);
PAINT RED (100 5925);
FORCENOTE
TDC=220A
(100 6410) 0;
DISPLAY LEFT (100 6410);
DISPLAY 0.936170 (100 6410);
PAINT RED (100 6410);
FORCENOTE
OCP=500A
(100 6250) 0;
DISPLAY LEFT (100 6250);
DISPLAY 0.936170 (100 6250);
PAINT WHITE (100 6250);
FORCENOTE
442A(UNDERSHOOT)
(100 6100) 0;
DISPLAY LEFT (100 6100);
DISPLAY 0.936170 (100 6100);
PAINT RED (100 6100);
FORCENOTE
RAIL
(-7321 700) 0;
DISPLAY LEFT (-7321 700);
DISPLAY 0.808511 (-7321 700);
PAINT WHITE (-7321 700);
FORCENOTE
TRACE WIDTH = 10MIL
(-7250 3925) 0;
DISPLAY LEFT (-7250 3925);
DISPLAY 1.021277 (-7250 3925);
PAINT WHITE (-7250 3925);
FORCENOTE
TRACE SPACING = 5MIL
(-7250 3850) 0;
DISPLAY LEFT (-7250 3850);
DISPLAY 1.021277 (-7250 3850);
PAINT WHITE (-7250 3850);
FORCENOTE
DIFFERENTIAL PAIR
(-7250 4000) 0;
DISPLAY LEFT (-7250 4000);
DISPLAY 1.021277 (-7250 4000);
PAINT WHITE (-7250 4000);
FORCENOTE
SVID / I2C ADDRESS
(-7421 825) 0;
DISPLAY LEFT (-7421 825);
DISPLAY 1.170213 (-7421 825);
PAINT WHITE (-7421 825);
FORCENOTE
PVCCIN_CPU0
(-7396 600) 0;
DISPLAY LEFT (-7396 600);
DISPLAY 0.638298 (-7396 600);
PAINT WHITE (-7396 600);
FORCENOTE
60H/C0H
(-6596 600) 0;
DISPLAY LEFT (-6596 600);
DISPLAY 0.638298 (-6596 600);
PAINT WHITE (-6596 600);
FORCENOTE
00H
(-6921 600) 0;
DISPLAY LEFT (-6921 600);
DISPLAY 0.638298 (-6921 600);
PAINT WHITE (-6921 600);
FORCENOTE
SVID
(-6946 700) 0;
DISPLAY LEFT (-6946 700);
DISPLAY 0.808511 (-6946 700);
PAINT WHITE (-6946 700);
FORCENOTE
I2C(7BIT/8BIT)
(-6596 700) 0;
DISPLAY LEFT (-6596 700);
DISPLAY 0.808511 (-6596 700);
PAINT WHITE (-6596 700);
FORCENOTE
20211013 MODIFY FOR GT
(-7575 6850) 0;
DISPLAY LEFT (-7575 6850);
DISPLAY 1.595745 (-7575 6850);
PAINT PINK (-7575 6850);
FORCENOTE
CONFIRM ADDRESS SETTING
(-5400 1525) 0;
DISPLAY LEFT (-5400 1525);
DISPLAY 1.021277 (-5400 1525);
PAINT SKYBLUE (-5400 1525);
FORCENOTE
IF SPS IS NOT USED
(-575 2950) 0;
DISPLAY LEFT (-575 2950);
DISPLAY 1.021277 (-575 2950);
FORCENOTE
CS# SHOULD BE TIDE TO GND
(-575 2875) 0;
DISPLAY LEFT (-575 2875);
DISPLAY 1.021277 (-575 2875);
FORCENOTE
DIFFERENTIAL PAIR
(-7575 2925) 0;
DISPLAY LEFT (-7575 2925);
DISPLAY 1.021277 (-7575 2925);
PAINT WHITE (-7575 2925);
FORCENOTE
TRACE WIDTH = 10MIL
(-7575 2850) 0;
DISPLAY LEFT (-7575 2850);
DISPLAY 1.021277 (-7575 2850);
PAINT WHITE (-7575 2850);
FORCENOTE
TRACE SPACING = 5MIL
(-7575 2775) 0;
DISPLAY LEFT (-7575 2775);
DISPLAY 1.021277 (-7575 2775);
PAINT WHITE (-7575 2775);
FORCENOTE
20220725 CONNECT TO CPLD
(-6025 2775) 0;
DISPLAY LEFT (-6025 2775);
DISPLAY 0.680851 (-6025 2775);
PAINT WHITE (-6025 2775);
QUIT
